VERSION = 2.0
UUNITS = MILS

#    refdes          !   symbol_x !   symbol_y ! rotation ! mirror ! symbol_name                      ! embedded_layer                  
#-----------------------------------------------------------------------------------------------------------------------
Y2                   !    1255.00 !    3885.00 !      180 !        ! SMC_Y4_126X098_V5_H032           !                                 
U34                  !    3695.00 !    2570.00 !      270 !        ! SOT23_6                          !                                 
C263                 !    5645.00 !    2345.00 !       90 !      m ! SMC_0201R                        !                                 
R53                  !    3543.00 !    4077.00 !        0 !      m ! SMC_0402R_H016                   !                                 
R46                  !    5741.00 !    3757.00 !      180 !        ! SMC_0402R_H016                   !                                 
J5                   !    6432.89 !    1520.63 !       90 !        ! S_F_H_2X6_RA_P100                !                                 
J13                  !     246.06 !    3431.50 !      270 !        ! P_F_USB_2X7_GH4_RA_P035_PIH      !                                 
SP20                 !    1450.00 !    5570.00 !        0 !        ! DUMMY                            !                                 
SP21                 !    1660.00 !    5245.00 !        0 !        ! DUMMY                            !                                 
SP22                 !    1675.00 !    4850.00 !        0 !        ! DUMMY                            !                                 
SP23                 !    1370.00 !    5105.00 !        0 !        ! DUMMY                            !                                 
SP24                 !    1840.00 !    4875.00 !        0 !        ! DUMMY                            !                                 
SP25                 !    1900.00 !    4970.00 !        0 !        ! DUMMY                            !                                 
SP26                 !    1900.00 !    4970.00 !        0 !        ! DUMMY                            !                                 
SP27                 !    2065.00 !    5160.00 !        0 !        ! DUMMY                            !                                 
SP28                 !    2275.00 !    5140.00 !        0 !        ! DUMMY                            !                                 
SP29                 !    2380.00 !    4880.00 !        0 !        ! DUMMY                            !                                 
SP30                 !    2555.00 !    4735.00 !        0 !        ! DUMMY                            !                                 
SP31                 !    2840.00 !    5050.00 !        0 !        ! DUMMY                            !                                 
SP32                 !    2580.00 !    5355.00 !        0 !        ! DUMMY                            !                                 
SP33                 !    2065.00 !    5185.00 !        0 !        ! DUMMY                            !                                 
SP34                 !    1730.00 !    4965.00 !        0 !        ! DUMMY                            !                                 
SP35                 !    1550.00 !    5075.00 !        0 !        ! DUMMY                            !                                 
SP36                 !    1640.00 !    5215.00 !        0 !        ! DUMMY                            !                                 
SP37                 !    2375.00 !    5255.00 !        0 !        ! DUMMY                            !                                 
SP38                 !    2630.00 !    4870.00 !        0 !        ! DUMMY                            !                                 
SP39                 !    2905.00 !    4900.00 !        0 !        ! DUMMY                            !                                 
SP40                 !    2775.00 !    5205.00 !        0 !        ! DUMMY                            !                                 
SP41                 !    2210.00 !    5225.00 !        0 !        ! DUMMY                            !                                 
SP42                 !    1765.00 !    5040.00 !        0 !        ! DUMMY                            !                                 
SP43                 !    1770.00 !    4785.00 !        0 !        ! DUMMY                            !                                 
SP44                 !    2250.00 !    4805.00 !        0 !        ! DUMMY                            !                                 
SP45                 !    2350.00 !    5005.00 !        0 !        ! DUMMY                            !                                 
SP46                 !    2250.00 !    5305.00 !        0 !        ! DUMMY                            !                                 
SP47                 !    2515.00 !    5335.00 !        0 !        ! DUMMY                            !                                 
SP48                 !    2735.00 !    5110.00 !        0 !        ! DUMMY                            !                                 
SP49                 !    2600.00 !    4995.00 !        0 !        ! DUMMY                            !                                 
SP50                 !    2205.00 !    5025.00 !        0 !        ! DUMMY                            !                                 
SP51                 !    2130.00 !    5135.00 !        0 !        ! DUMMY                            !                                 
SP52                 !    1960.00 !    5180.00 !        0 !        ! DUMMY                            !                                 
SP53                 !    1910.00 !    5145.00 !        0 !        ! DUMMY                            !                                 
SP54                 !    1975.00 !    4995.00 !        0 !        ! DUMMY                            !                                 
SP55                 !    2050.00 !    4950.00 !        0 !        ! DUMMY                            !                                 
SP56                 !    2155.00 !    4935.00 !        0 !        ! DUMMY                            !                                 
SP57                 !    2260.00 !    4995.00 !        0 !        ! DUMMY                            !                                 
SP58                 !    2265.00 !    5100.00 !        0 !        ! DUMMY                            !                                 
SP59                 !    2255.00 !    5120.00 !        0 !        ! DUMMY                            !                                 
SP60                 !    2110.00 !    5185.00 !        0 !        ! DUMMY                            !                                 
SP61                 !    1995.00 !    5190.00 !        0 !        ! DUMMY                            !                                 
SP62                 !    1890.00 !    5175.00 !        0 !        ! DUMMY                            !                                 
SP63                 !    1820.00 !    5160.00 !        0 !        ! DUMMY                            !                                 
SP64                 !    1735.00 !    5135.00 !        0 !        ! DUMMY                            !                                 
SP65                 !    1735.00 !    5135.00 !        0 !        ! DUMMY                            !                                 
SP66                 !    1830.00 !    5005.00 !        0 !        ! DUMMY                            !                                 
SP67                 !    1860.00 !    4990.00 !        0 !        ! DUMMY                            !                                 
SP68                 !    1955.00 !    4970.00 !        0 !        ! DUMMY                            !                                 
SP69                 !    2010.00 !    4965.00 !        0 !        ! DUMMY                            !                                 
SP70                 !    2200.00 !    5160.00 !        0 !        ! DUMMY                            !                                 
SP71                 !    2200.00 !    5180.00 !        0 !        ! DUMMY                            !                                 
SP72                 !    1985.00 !    5195.00 !        0 !        ! DUMMY                            !                                 
SP73                 !    1960.00 !    5185.00 !        0 !        ! DUMMY                            !                                 
SP74                 !    1500.00 !    5010.00 !        0 !        ! DUMMY                            !                                 
SP75                 !    1450.00 !    4945.00 !        0 !        ! DUMMY                            !                                 
SP76                 !    1520.00 !    4850.00 !        0 !        ! DUMMY                            !                                 
SP77                 !    1920.00 !    4825.00 !        0 !        ! DUMMY                            !                                 
SP78                 !    2065.00 !    4820.00 !        0 !        ! DUMMY                            !                                 
SP79                 !    2175.00 !    4870.00 !        0 !        ! DUMMY                            !                                 
SP80                 !    2245.00 !    4990.00 !        0 !        ! DUMMY                            !                                 
SP81                 !    2220.00 !    5080.00 !        0 !        ! DUMMY                            !                                 
U19                  !     775.00 !     828.00 !      270 !        ! SOP8_173X118_P0256               !                                 
C42                  !    1456.00 !    4036.00 !      180 !      m ! SMC_0402R_H022                   !                                 
C54                  !    3543.00 !    3942.00 !        0 !      m ! SMC_0402R_H022                   !                                 
U31                  !    1859.00 !    3463.00 !        0 !      m ! SOP8_154_P050_V1                 !                                 
CR1                  !    1640.00 !    3270.00 !      180 !        ! SMC_CR_067X049_V1                !                                 
CR2                  !    1640.00 !    3170.00 !      180 !        ! SMC_CR_067X049_V1                !                                 
L4                   !    1090.00 !    3485.00 !      270 !      m ! SMC_0603R_H037                   !                                 
L10                  !    3770.00 !     890.00 !       90 !      m ! SMC_0603R_H037                   !                                 
L14                  !    4270.00 !     805.00 !       90 !      m ! SMC_0603R_H037                   !                                 
L17                  !    6060.00 !    2324.00 !      180 !        ! SMC_0603R_H037                   !                                 
L18                  !     925.48 !    2632.00 !      180 !        ! SMC_0603R_H037                   !                                 
L19                  !    3491.00 !    2536.00 !       90 !        ! SMC_0603R_H037                   !                                 
L22                  !    1320.00 !    3575.00 !       90 !      m ! SMC_0603R_H037                   !                                 
L12                  !    5210.00 !    1725.00 !        0 !        ! SMC_0603R_H030                   !                                 
L15                  !    5120.00 !    3880.00 !       90 !        ! SMC_0603R_H030                   !                                 
L16                  !    4625.00 !    3860.00 !      180 !        ! SMC_0603R_H030                   !                                 
L24                  !    1455.00 !    3165.00 !      270 !        ! SMC_0603R_H030                   !                                 
L33                  !    3655.00 !    2205.00 !      180 !        ! SMC_0603R_H030                   !                                 
L34                  !    3645.00 !    1470.00 !      180 !        ! SMC_0603R_H030                   !                                 
L35                  !    3645.00 !    1395.00 !        0 !      m ! SMC_0603R_H030                   !                                 
U18                  !    1123.00 !    3349.00 !      270 !        ! QFP64_394_P0197_V1               !                                 
L5                   !    5597.00 !    1838.00 !      270 !        ! SMC_L_287X260_V1_H197            !                                 
U39                  !    3980.00 !    3443.00 !      270 !        ! SOT363_V2                        !                                 
U40                  !    4175.00 !    3445.00 !      270 !        ! SOT363_V2                        !                                 
U32                  !     821.00 !    2337.00 !       90 !        ! SOP8_118_P0256_V2                !                                 
Q1                   !    4435.00 !    3575.00 !        0 !        ! SOT23_V1_H044                    !                                 
Q2                   !    3010.00 !    2180.00 !       90 !      m ! SOT23_V1_H044                    !                                 
Q3                   !    3015.00 !    2315.00 !      270 !      m ! SOT23_V1_H045                    !                                 
R463                 !    1175.00 !    3585.00 !      270 !      m ! SMC_0402R                        !                                 
R186                 !    3837.00 !    2680.00 !        0 !        ! SMC_0402R_H016                   !                                 
R496                 !     455.00 !    1199.00 !      270 !        ! SMC_0402R_H016                   !                                 
R497                 !     443.00 !     668.00 !      270 !        ! SMC_0402R_H016                   !                                 
R498                 !     452.00 !    2347.00 !      270 !        ! SMC_0402R_H016                   !                                 
R499                 !     455.00 !    1665.00 !       90 !        ! SMC_0402R_H016                   !                                 
R168                 !    3470.00 !    2355.00 !       90 !      m ! SMC_0402R_H016                   !                                 
R455                 !    1250.00 !    3750.00 !      180 !        ! SMC_0402R_H016                   !                                 
R436                 !    4442.80 !    1823.74 !      270 !      m ! SMC_0402R_C_H016                 !                                 
R437                 !    4482.17 !    1823.74 !      270 !      m ! SMC_0402R_C_H016                 !                                 
R502                 !    4580.59 !    1843.43 !        0 !      m ! SMC_0402R_C_H016                 !                                 
R30                  !    1456.00 !    3991.00 !        0 !      m ! SMC_0402R_H016                   !                                 
R207                 !    4350.00 !    2440.00 !      270 !      m ! SMC_0402R_H016                   !                                 
R122                 !     455.00 !    1104.90 !      270 !        ! SMC_0402R_H016                   !                                 
R123                 !     530.00 !     676.00 !      270 !      m ! SMC_0402R_H016                   !                                 
R126                 !     455.00 !    1760.00 !       90 !        ! SMC_0402R_H016                   !                                 
R127                 !     464.52 !    2254.00 !      270 !        ! SMC_0402R_H016                   !                                 
R367                 !     480.00 !    1465.00 !       90 !        ! SMC_0402R_H016                   !                                 
R370                 !     485.00 !     905.00 !       90 !        ! SMC_0402R_H016                   !                                 
R371                 !     478.00 !    2590.00 !       90 !        ! SMC_0402R_H016                   !                                 
R372                 !     480.00 !    2070.00 !       90 !        ! SMC_0402R_H016                   !                                 
U30                  !    4155.00 !    3675.00 !        0 !        ! SOP16_173_P0256                  !                                 
U37                  !    5005.00 !     830.00 !        0 !        ! SOP16_173_P0256                  !                                 
U38                  !    4289.00 !    3156.00 !        0 !        ! SOP16_173_P0256                  !                                 
C286                 !    3543.00 !    4032.00 !      180 !      m ! SMC_0402R_H022                   !                                 
C293                 !    5825.00 !     775.00 !      270 !      m ! SMC_0402R_H022                   !                                 
C294                 !    4545.00 !    2895.00 !      180 !      m ! SMC_0402R_H022                   !                                 
P3                   !    6340.55 !    3509.84 !      270 !        ! P_M_H_2X3_NP2_RA_P165_V1         !                                 
R255                 !    5754.00 !    2345.00 !      270 !        ! SMC_0402R_H016                   !                                 
R34                  !    1456.00 !    4142.00 !        0 !        ! SMC_0402R_H016                   !                                 
R251                 !    5754.00 !    2345.00 !       90 !      m ! SMC_0402R_H016                   !                                 
U3                   !    2801.00 !     605.00 !        0 !        ! SC70_5V1                         !                                 
J9                   !     755.00 !    1525.00 !      180 !        ! S_M_H_2X2_S_P100_V3              !                                 
J17                  !    3340.00 !    2815.00 !       90 !        ! S_M_H_2X2_S_P100_V3              !                                 
U29                  !    3390.00 !    2314.00 !        0 !        ! LGA28_205X150_P0197              !                                 
J1                   !     160.39 !    1283.46 !        0 !        ! P_F_JACK_1P_GH4_RA_P200          !                                 
J2                   !     160.39 !     712.60 !        0 !        ! P_F_JACK_1P_GH4_RA_P200          !                                 
J3                   !     160.39 !    2425.20 !        0 !        ! P_F_JACK_1P_GH4_RA_P200          !                                 
J4                   !     160.39 !    1854.33 !        0 !        ! P_F_JACK_1P_GH4_RA_P200          !                                 
DS14                 !      59.06 !    1539.37 !       90 !        ! SMC_DS4_098X039                  !                                 
DS15                 !      59.06 !     968.50 !       90 !        ! SMC_DS4_098X039                  !                                 
DS16                 !      59.06 !    2681.10 !       90 !        ! SMC_DS4_098X039                  !                                 
DS17                 !      59.06 !    2110.24 !       90 !        ! SMC_DS4_098X039                  !                                 
DS18                 !      59.06 !    3251.97 !       90 !        ! SMC_DS4_098X039                  !                                 
U33                  !    4144.00 !    3992.00 !      180 !        ! QFN29_197_P0197_TR115SQ_V1       !                                 
U13                  !     547.24 !    1283.46 !      270 !        ! SOP8_091_P0197_H035              !                                 
U14                  !     547.24 !     712.60 !      270 !        ! SOP8_091_P0197_H035              !                                 
U15                  !     547.24 !    2425.20 !      270 !        ! SOP8_091_P0197_H035              !                                 
U16                  !     547.24 !    1854.33 !      270 !        ! SOP8_091_P0197_H035              !                                 
ME9                  !     295.28 !    3730.31 !        0 !        ! MTH125C236N_V8                   !                                 
ME10                 !     295.28 !     368.11 !        0 !        ! MTH125C236N_V8                   !                                 
ME11                 !    6400.39 !    4178.35 !        0 !        ! MTH125C236N_V8                   !                                 
ME12                 !    6400.39 !     653.54 !        0 !        ! MTH125C236N_V8                   !                                 
ME5                  !    1460.67 !    2680.43 !        0 !        ! MTH100C240N                      !                                 
ME6                  !    2685.67 !    2559.43 !        0 !        ! MTH100C240N                      !                                 
ME7                  !    1435.67 !    1060.43 !        0 !        ! MTH100C240N                      !                                 
ME8                  !    2685.67 !    1121.43 !        0 !        ! MTH100C240N                      !                                 
FU3                  !    2845.00 !    2195.00 !       90 !      m ! SMC_0603R_H024                   !                                 
ME1                  !    2559.06 !    4120.08 !        0 !        ! P_NUT_166CT244CB198_V1_H380      !                                 
ME2                  !    2559.06 !    3096.46 !        0 !        ! P_NUT_166CT244CB198_V1_H380      !                                 
ME3                  !    4940.94 !    4120.08 !        0 !        ! P_NUT_166CT244CB198_V1_H380      !                                 
ME4                  !    4940.94 !    3096.46 !        0 !        ! P_NUT_166CT244CB198_V1_H380      !                                 
R357                 !    2850.00 !    2310.00 !       90 !      m ! SMC_0805R_H026                   !                                 
U7                   !    1014.00 !     691.00 !        0 !        ! SOT23_5_H039                     !                                 
MAC_PIN1             !    1260.67 !    2640.43 !        0 !        ! P_NUT_079C100                    !                                 
MAC_PIN2             !    1260.67 !    1840.43 !        0 !        ! P_NUT_079C100                    !                                 
MAC_PIN3             !    1260.67 !    1040.43 !        0 !        ! P_NUT_079C100                    !                                 
MAC_PIN4             !    2860.67 !    1040.43 !        0 !        ! P_NUT_079C100                    !                                 
MAC_PIN5             !    2860.67 !    2640.43 !        0 !        ! P_NUT_079C100                    !                                 
MAC_PIN6             !    2778.67 !     934.43 !        0 !        ! P_NUT_079C100                    !                                 
MAC_PIN7             !    2659.67 !     934.43 !        0 !        ! P_NUT_079C100                    !                                 
MAC_PIN8             !    2539.67 !     934.43 !        0 !        ! P_NUT_079C100                    !                                 
R442                 !     595.00 !    3575.00 !       90 !        ! SMC_0402R_H016                   !                                 
R445                 !     610.00 !    3290.00 !        0 !        ! SMC_0402R_H016                   !                                 
R52                  !    3543.00 !    4077.00 !        0 !        ! SMC_0402R_H016                   !                                 
C4                   !    5721.00 !    3712.00 !      180 !        ! SMC_0201R                        !                                 
U28                  !     789.48 !    2661.00 !      180 !        ! LGA10_079_P0197                  !                                 
U27                  !    5990.00 !    2094.00 !       90 !        ! DFN9_098_P0197_TR039X071         !                                 
C314                 !    4375.00 !    3965.00 !        0 !        ! SMC_0402R_H022                   !                                 
C287                 !    2105.00 !     615.00 !       90 !        ! SMC_0402R_H022                   !                                 
C289                 !    2155.00 !     635.00 !      270 !      m ! SMC_0402R_H022                   !                                 
C274                 !    6050.00 !    2225.00 !        0 !        ! SMC_0402R_H022                   !                                 
C277                 !     930.00 !    2728.00 !        0 !        ! SMC_0402R_H022                   !                                 
C280                 !    3384.84 !    2532.00 !       90 !        ! SMC_0402R_H022                   !                                 
C246                 !    4275.00 !     940.00 !      270 !      m ! SMC_0402R_H022                   !                                 
C247                 !    3790.00 !     970.00 !      180 !        ! SMC_0402R_H022                   !                                 
C90                  !    1035.00 !    3115.00 !       90 !      m ! SMC_0402R_H026                   !                                 
C91                  !    1375.00 !    3580.00 !       90 !      m ! SMC_0402R_H026                   !                                 
C98                  !    1085.00 !    3585.00 !      270 !      m ! SMC_0402R_H026                   !                                 
C99                  !    1220.00 !    3585.00 !      270 !      m ! SMC_0402R_H026                   !                                 
C93                  !    4600.28 !    1548.16 !      270 !      m ! SMC_0402R_C_H026                 !                                 
C117                 !    3950.67 !    1528.47 !      180 !      m ! SMC_0402R_C_H026                 !                                 
C120                 !    4206.58 !    1626.89 !       90 !      m ! SMC_0402R_C_H026                 !                                 
C128                 !    4444.11 !    1755.00 !      180 !      m ! SMC_0402R_H026                   !                                 
C131                 !    4009.73 !    1626.89 !       90 !      m ! SMC_0402R_C_H026                 !                                 
C138                 !    4462.49 !    1685.95 !      180 !      m ! SMC_0402R_C_H026                 !                                 
C154                 !    4679.02 !    2138.71 !      270 !      m ! SMC_0402R_C_H026                 !                                 
C159                 !    4045.00 !    2215.00 !        0 !      m ! SMC_0402R_H026                   !                                 
C160                 !    4521.54 !    1390.66 !      270 !      m ! SMC_0402R_C_H026                 !                                 
C163                 !    4475.85 !    2220.00 !        0 !      m ! SMC_0402R_H026                   !                                 
C167                 !    3990.04 !    1922.17 !        0 !      m ! SMC_0402R_C_H026                 !                                 
C170                 !    4049.10 !    1941.86 !      270 !      m ! SMC_0402R_C_H026                 !                                 
C198                 !    3582.00 !    2782.00 !      270 !        ! SMC_0402R_H026                   !                                 
C125                 !    3785.00 !    1335.00 !       90 !      m ! SMC_0805R_H057                   !                                 
C137                 !    3705.00 !    1615.00 !       90 !        ! SMC_0805R_H057                   !                                 
C143                 !    3460.00 !    1345.00 !       90 !      m ! SMC_0805R_H057                   !                                 
C155                 !    3515.00 !    1615.00 !       90 !        ! SMC_0805R_H057                   !                                 
C173                 !    5240.00 !    1240.00 !        0 !        ! SMC_0805R_H057                   !                                 
C179                 !    5400.00 !    1820.00 !      270 !      m ! SMC_0805R_H057                   !                                 
C269                 !    5690.00 !    1610.00 !        0 !        ! SMC_0805R_H057                   !                                 
C270                 !    5350.00 !    1820.00 !       90 !        ! SMC_0805R_H057                   !                                 
C271                 !    5390.00 !    1630.00 !      270 !        ! SMC_0805R_H057                   !                                 
C172                 !    4035.00 !    2325.00 !        0 !      m ! SMC_1210R_H110                   !                                 
C174                 !    4740.00 !    2489.00 !       90 !        ! SMC_1210R_H110                   !                                 
C175                 !    5245.00 !    1595.00 !        0 !        ! SMC_1210R_H110                   !                                 
C176                 !    5245.00 !    1345.00 !        0 !        ! SMC_1210R_H110                   !                                 
C177                 !    5245.00 !    1470.00 !        0 !        ! SMC_1210R_H110                   !                                 
P1                   !    2848.60 !    1840.42 !      270 !        ! S_M_H_2X10_S_P0197               !                                 
P2                   !    4851.02 !    3790.16 !       90 !        ! S_F_H_2X4_S_P0787_V1             !                                 
L3                   !    3185.00 !    2880.00 !      270 !      m ! SMC_0603R_H030                   !                                 
L7                   !    1561.00 !    3776.00 !        0 !        ! SMC_0603R_H030                   !                                 
L8                   !    3438.00 !    4202.00 !      180 !        ! SMC_0603R_H030                   !                                 
L9                   !    5395.00 !    2256.00 !      270 !        ! SMC_0603R_H030                   !                                 
L20                  !     571.00 !    3872.00 !       90 !        ! SMC_0603R_H030                   !                                 
L21                  !    2260.00 !     650.00 !      270 !      m ! SMC_0603R_H030                   !                                 
L23                  !    1760.00 !    3160.00 !      270 !        ! SMC_0603R_H030                   !                                 
L6                   !    4933.00 !    2493.00 !       90 !        ! SMC_0603R_H030                   !                                 
L11                  !    3681.00 !    3099.00 !        0 !        ! SMC_0603R_H030                   !                                 
L13                  !    5700.00 !     960.00 !      270 !        ! SMC_0603R_H030                   !                                 
FU1                  !    5506.00 !    3569.00 !      180 !        ! SMC_0603R_H022                   !                                 
U41                  !    1680.00 !    3015.00 !        0 !        ! DFN11_118_P0197_TR057X071_VIA    !                                 
U20                  !    3912.00 !    2945.00 !       90 !        ! DFN11_118_P0197_TR057X071_VIA    !                                 
U21                  !    5108.00 !    2707.00 !      180 !        ! DFN11_118_P0197_TR057X071_VIA    !                                 
U25                  !    5625.00 !     679.00 !        0 !        ! DFN11_118_P0197_TR057X071_VIA    !                                 
U23                  !    3625.00 !    3310.00 !      180 !        ! SOP8_208_P050_V2                 !                                 
U22                  !    4356.00 !    2876.00 !      180 !        ! DFN13_118_P0197_TR071X096_VIA    !                                 
Y3                   !    4364.00 !     865.00 !       90 !        ! SMC_Y6_126X197                   !                                 
Y4                   !    3980.00 !     825.00 !       90 !        ! SMC_Y6_197X276                   !                                 
R166                 !    4960.00 !    2615.00 !       90 !        ! SMC_0402R                        !                                 
R177                 !    3814.00 !    3092.00 !      180 !      m ! SMC_0402R                        !                                 
R228                 !    5775.00 !     775.00 !      270 !        ! SMC_0402R                        !                                 
R454                 !    2105.00 !    3430.00 !       90 !      m ! SMC_0402R                        !                                 
R232                 !    5557.00 !     726.00 !       90 !      m ! SMC_0402R                        !                                 
R233                 !    5425.00 !     690.00 !      180 !      m ! SMC_0402R                        !                                 
R491                 !    1500.00 !    3000.00 !        0 !      m ! SMC_0402R_H014                   !                                 
R32                  !    1456.00 !    4142.00 !        0 !      m ! SMC_0402R_H014                   !                                 
R188                 !    5278.00 !    2632.00 !      270 !      m ! SMC_0402R_H014                   !                                 
R189                 !    3837.00 !    2725.00 !        0 !        ! SMC_0402R_H014                   !                                 
R190                 !    5328.00 !    2632.00 !       90 !        ! SMC_0402R_H014                   !                                 
R185                 !    3837.00 !    2775.00 !        0 !        ! SMC_0402R                        !                                 
R187                 !    5278.00 !    2632.00 !       90 !        ! SMC_0402R                        !                                 
R231                 !    5425.00 !     690.00 !        0 !        ! SMC_0402R                        !                                 
R239                 !    4343.00 !     973.00 !      180 !        ! SMC_0402R_H016                   !                                 
R240                 !    3985.00 !     970.00 !      180 !        ! SMC_0402R_H016                   !                                 
R241                 !    4439.00 !     973.00 !        0 !        ! SMC_0402R_H016                   !                                 
R242                 !    4080.00 !     970.00 !        0 !        ! SMC_0402R_H016                   !                                 
R1                   !    1194.70 !     708.60 !        0 !      m ! SMC_0402R_H016                   !                                 
R2                   !     799.00 !     732.00 !       90 !      m ! SMC_0402R_H016                   !                                 
R169                 !    6145.00 !    4115.00 !       90 !      m ! SMC_0402R_H016                   !                                 
R118                 !    5910.00 !    4110.00 !       90 !      m ! SMC_0402R_H016                   !                                 
R119                 !    6025.00 !    4110.00 !       90 !      m ! SMC_0402R_H016                   !                                 
R279                 !    6027.00 !    4240.00 !       90 !      m ! SMC_0402R_H016                   !                                 
R280                 !    6140.00 !    4240.00 !       90 !      m ! SMC_0402R_H016                   !                                 
R138                 !    5435.00 !    4145.00 !      270 !      m ! SMC_0402R_H016                   !                                 
R208                 !    5323.00 !    4180.01 !       90 !      m ! SMC_0402R_H016                   !                                 
R210                 !    5273.00 !    4180.01 !      270 !      m ! SMC_0402R_H016                   !                                 
R225                 !    5775.00 !     775.00 !       90 !      m ! SMC_0402R_H016                   !                                 
R226                 !    4545.00 !    2945.00 !        0 !      m ! SMC_0402R_H016                   !                                 
R257                 !    5435.00 !    4240.00 !       90 !      m ! SMC_0402R_H016                   !                                 
R258                 !    5555.00 !    4240.00 !       90 !      m ! SMC_0402R_H016                   !                                 
R259                 !    5670.00 !    4240.00 !       90 !      m ! SMC_0402R_H016                   !                                 
R261                 !    5790.00 !    4240.00 !       90 !      m ! SMC_0402R_H016                   !                                 
U24                  !    4305.00 !    1745.00 !       90 !        ! BGA484_906_P0394_V3              !                                 
C310                 !     500.00 !    1570.00 !      180 !        ! SMC_0201R                        !                                 
C311                 !     514.00 !    1000.00 !        0 !        ! SMC_0201R                        !                                 
C317                 !     507.00 !    2680.00 !        0 !        ! SMC_0201R                        !                                 
C318                 !     506.00 !    2166.00 !      180 !        ! SMC_0201R                        !                                 
C264                 !    5640.00 !    2340.00 !       90 !        ! SMC_0201R                        !                                 
C43                  !    1461.00 !    4031.00 !      180 !        ! SMC_0201R                        !                                 
C55                  !    3538.00 !    3947.00 !        0 !        ! SMC_0201R                        !                                 
C86                  !    1280.00 !    3790.00 !      180 !        ! SMC_0201R                        !                                 
C87                  !    1225.00 !    3790.00 !        0 !        ! SMC_0201R                        !                                 
C267                 !    5695.00 !    2345.00 !      270 !        ! SMC_0201R                        !                                 
C11                  !    1456.00 !    4086.00 !        0 !        ! SMC_0201R                        !                                 
C16                  !    3538.00 !    3892.00 !      180 !        ! SMC_0201R                        !                                 
C307                 !    1725.00 !    2900.00 !      180 !        ! SMC_0201R                        !                                 
C8                   !    5496.00 !    3912.00 !      180 !        ! SMC_0201R                        !                                 
C190                 !    3982.00 !    3090.00 !       90 !        ! SMC_0201R                        !                                 
C191                 !    4963.00 !    2777.00 !      180 !        ! SMC_0201R                        !                                 
C192                 !    3952.00 !    2774.00 !        0 !        ! SMC_0201R                        !                                 
C193                 !    5280.00 !    2725.00 !        0 !        ! SMC_0201R                        !                                 
C231                 !    5770.00 !     609.00 !        0 !        ! SMC_0201R                        !                                 
C234                 !    5450.00 !     635.00 !      180 !        ! SMC_0201R                        !                                 
C258                 !    5510.00 !    2340.00 !      270 !        ! SMC_0201R                        !                                 
C75                  !    1461.00 !    3901.00 !        0 !        ! SMC_0201R                        !                                 
C77                  !    3537.00 !    4121.00 !      180 !        ! SMC_0201R                        !                                 
C266                 !    5610.00 !    1980.00 !      180 !      m ! SMC_0402R_H022                   !                                 
C45                  !    1800.00 !    4045.00 !      270 !      m ! SMC_0402R_H022                   !                                 
C57                  !    3185.00 !    3900.00 !       90 !      m ! SMC_0402R_H022                   !                                 
C259                 !    5600.00 !    2345.00 !       90 !        ! SMC_0402R_H022                   !                                 
C31                  !    1456.00 !    3991.00 !      180 !        ! SMC_0402R_H022                   !                                 
C49                  !    3543.00 !    3987.00 !        0 !        ! SMC_0402R_H022                   !                                 
C284                 !    1815.00 !    3260.00 !        0 !        ! SMC_0805R_H057                   !                                 
C158                 !    3645.00 !    2230.00 !      180 !      m ! SMC_0805R_H057                   !                                 
C164                 !    3765.00 !    1060.00 !      180 !      m ! SMC_0805R_H057                   !                                 
C168                 !    4966.00 !    1263.00 !        0 !      m ! SMC_0805R_H057                   !                                 
C291                 !    3765.00 !    1060.00 !        0 !        ! SMC_0805R_H057                   !                                 
C292                 !    4966.00 !    1264.00 !      180 !        ! SMC_0805R_H057                   !                                 
C180                 !    3662.00 !    2985.00 !       90 !      m ! SMC_0805R_H057                   !                                 
C181                 !    5047.00 !    2454.00 !      180 !      m ! SMC_0805R_H057                   !                                 
C224                 !    5575.00 !     965.00 !      270 !        ! SMC_0805R_H057                   !                                 
C232                 !    4455.00 !    2705.00 !      270 !        ! SMC_0805R_H057                   !                                 
C238                 !    4167.00 !    2936.00 !      180 !        ! SMC_0805R_H057                   !                                 
C240                 !    4167.00 !    2855.00 !      180 !        ! SMC_0805R_H057                   !                                 
C241                 !    4167.00 !    2936.00 !        0 !      m ! SMC_0805R_H057                   !                                 
C243                 !    4167.00 !    2855.00 !        0 !      m ! SMC_0805R_H057                   !                                 
C13                  !    2236.00 !    3861.00 !      270 !        ! SMC_0805R_H057                   !                                 
C14                  !    2186.00 !    4071.00 !       90 !        ! SMC_0805R_H057                   !                                 
C15                  !    2261.00 !    4071.00 !       90 !        ! SMC_0805R_H057                   !                                 
C20                  !    3480.00 !    3685.00 !       90 !        ! SMC_0805R_H057                   !                                 
C21                  !    3320.00 !    3685.00 !       90 !        ! SMC_0805R_H057                   !                                 
C22                  !    3400.00 !    3685.00 !       90 !        ! SMC_0805R_H057                   !                                 
U10                  !    2440.00 !    2240.00 !      270 !      m ! SC70_5V1                         !                                 
CR3                  !    5316.00 !    3607.00 !      270 !      m ! SMC_CR_170X143_V2                !                                 
CR10                 !    5421.00 !    3306.00 !        0 !        ! SMC_CR_270X232_V1                !                                 
CR12                 !     783.00 !    3941.00 !        0 !        ! DPAK_3_V3                        !                                 
U2                   !    1772.70 !     665.00 !      180 !        ! SOP8_154_P050_V1                 !                                 
L1                   !    1961.00 !    3976.00 !        0 !        ! SMC_L_287X268_V3                 !                                 
L2                   !    3050.00 !    3865.00 !      270 !        ! SMC_L_287X268_V3                 !                                 
U35                  !    2135.00 !    3175.00 !      270 !        ! SOP8_118_P0256_V2                !                                 
U36                  !    6175.00 !    1045.00 !        0 !        ! SOP8_118_P0256_V2                !                                 
U8                   !     460.00 !    2990.00 !        0 !      m ! SOP8_118_P0256_V2                !                                 
U1                   !    5536.00 !    3737.00 !      180 !        ! QFN26_118X197_P197_TR049X010     !                                 
R246                 !    5555.00 !    2345.00 !      270 !      m ! SMC_0402R_H016                   !                                 
R48                  !    1456.00 !    3946.00 !        0 !      m ! SMC_0402R_H016                   !                                 
R11                  !    5341.00 !    3957.00 !        0 !        ! SMC_0402R_H016                   !                                 
R489                 !    1505.00 !    2950.00 !      180 !        ! SMC_0402R                        !                                 
R14                  !    5580.00 !    3915.00 !        0 !        ! SMC_0402R                        !                                 
R16                  !    5741.00 !    3907.00 !      180 !      m ! SMC_0402R                        !                                 
R38                  !    3515.00 !    3780.00 !      180 !        ! SMC_0402R_H016                   !                                 
R19                  !    1194.70 !     708.60 !      180 !        ! SMC_0402R_H016                   !                                 
R317                 !    4245.00 !    4065.00 !      180 !      m ! SMC_0402R_H016                   !                                 
R318                 !    4245.00 !    4115.00 !      180 !      m ! SMC_0402R_H016                   !                                 
R1991                !    1194.80 !     658.70 !      180 !      m ! SMC_0402R_H016                   !                                 
R146                 !    3277.00 !    3385.00 !      180 !      m ! SMC_0402R_H016                   !                                 
R36                  !    3543.00 !    3987.00 !      180 !      m ! SMC_0402R_H016                   !                                 
R47                  !    1446.00 !    3851.00 !      180 !      m ! SMC_0402R_H016                   !                                 
R49                  !    1561.00 !    3776.00 !        0 !      m ! SMC_0402R_H016                   !                                 
R51                  !    3560.00 !    4130.00 !        0 !      m ! SMC_0402R_H016                   !                                 
R130                 !     995.00 !    3585.00 !       90 !      m ! SMC_0402R_H016                   !                                 
R147                 !     829.00 !    1639.00 !        0 !      m ! SMC_0402R_H016                   !                                 
R148                 !     829.00 !    1549.00 !        0 !      m ! SMC_0402R_H016                   !                                 
R172                 !    3919.00 !    2531.00 !      270 !        ! SMC_0402R_H016                   !                                 
R237                 !    4545.00 !    2845.00 !        0 !        ! SMC_0402R_H016                   !                                 
R247                 !    5465.00 !    2345.00 !       90 !      m ! SMC_0402R_H016                   !                                 
R283                 !    3860.00 !    2531.00 !      270 !        ! SMC_0402R_H016                   !                                 
R285                 !    3801.00 !    2531.00 !      270 !        ! SMC_0402R_H016                   !                                 
R292                 !    4037.00 !    2531.00 !      270 !        ! SMC_0402R_H016                   !                                 
R295                 !    4345.00 !    2975.00 !      180 !      m ! SMC_0402R_H016                   !                                 
R308                 !    4093.00 !    2531.00 !      270 !        ! SMC_0402R_H016                   !                                 
R325                 !    4209.00 !    2531.00 !      270 !        ! SMC_0402R_H016                   !                                 
R327                 !    4150.00 !    2531.00 !      270 !        ! SMC_0402R_H016                   !                                 
R355                 !    4370.00 !    1100.00 !       90 !      m ! SMC_0402R_H016                   !                                 
R358                 !    4415.00 !    1100.00 !       90 !      m ! SMC_0402R_H016                   !                                 
R359                 !    4437.50 !    1123.00 !        0 !        ! SMC_0402R_H016                   !                                 
R360                 !    4345.50 !    1123.00 !      180 !        ! SMC_0402R_H016                   !                                 
R438                 !    4585.00 !    1160.00 !      270 !        ! SMC_0402R_H016                   !                                 
R439                 !    4530.00 !    1160.00 !      270 !        ! SMC_0402R_H016                   !                                 
R440                 !    4530.00 !    1160.00 !       90 !      m ! SMC_0402R_H016                   !                                 
R441                 !    4585.00 !    1160.00 !       90 !      m ! SMC_0402R_H016                   !                                 
R444                 !    2125.00 !    3360.00 !        0 !      m ! SMC_0402R_H016                   !                                 
R446                 !    2125.00 !    3550.00 !        0 !      m ! SMC_0402R_H016                   !                                 
R447                 !    2125.00 !    3500.00 !        0 !      m ! SMC_0402R_H016                   !                                 
R488                 !    1885.00 !    2960.00 !      270 !      m ! SMC_0402R_H016                   !                                 
R490                 !    1530.00 !    3025.00 !      270 !        ! SMC_0402R_H016                   !                                 
R403                 !    5452.00 !    2792.00 !       90 !      m ! SMC_0402R_H016                   !                                 
R404                 !    5452.00 !    2943.50 !       90 !      m ! SMC_0402R_H016                   !                                 
R405                 !    5452.00 !    3040.00 !       90 !      m ! SMC_0402R_H016                   !                                 
R165                 !    3912.00 !    3092.00 !      180 !      m ! SMC_0402R_H016                   !                                 
R170                 !    3978.00 !    2531.00 !      270 !        ! SMC_0402R_H016                   !                                 
R174                 !    4961.00 !    2707.00 !      270 !      m ! SMC_0402R_H016                   !                                 
R213                 !    4395.00 !    2440.00 !      270 !        ! SMC_0402R_H016                   !                                 
R215                 !    4530.00 !    2440.00 !       90 !      m ! SMC_0402R_H016                   !                                 
R219                 !    4395.00 !    2440.00 !       90 !      m ! SMC_0402R_H016                   !                                 
R227                 !    5772.00 !     679.00 !       90 !      m ! SMC_0402R_H016                   !                                 
R4                   !    5741.00 !    3467.00 !      180 !        ! SMC_0402R_H016                   !                                 
R5                   !    5741.00 !    3517.00 !        0 !        ! SMC_0402R_H016                   !                                 
R10                  !    5741.00 !    3857.00 !      180 !      m ! SMC_0402R_H016                   !                                 
R12                  !    5485.43 !    3967.00 !      180 !        ! SMC_0402R_H016                   !                                 
R13                  !    5580.00 !    3960.00 !      180 !        ! SMC_0402R_H016                   !                                 
R15                  !    5741.00 !    3907.00 !      180 !        ! SMC_0402R_H016                   !                                 
R164                 !    3760.00 !    2405.00 !       90 !        ! SMC_0402R_H016                   !                                 
R435                 !    4575.00 !    2440.00 !       90 !        ! SMC_0402R_H016                   !                                 
R466                 !     890.00 !    3455.00 !      180 !      m ! SMC_0402R_H016                   !                                 
R474                 !    4715.00 !     865.00 !        0 !        ! SMC_0402R_H016                   !                                 
R475                 !    4715.00 !     785.00 !        0 !        ! SMC_0402R_H016                   !                                 
R476                 !    5270.00 !     760.00 !      180 !        ! SMC_0402R_H016                   !                                 
R477                 !    5270.00 !     820.00 !      180 !        ! SMC_0402R_H016                   !                                 
R478                 !     725.00 !    3245.00 !      180 !      m ! SMC_0402R_H016                   !                                 
R479                 !     725.00 !    3200.00 !      180 !      m ! SMC_0402R_H016                   !                                 
R480                 !    1025.00 !    2960.00 !       90 !        ! SMC_0402R_H016                   !                                 
R481                 !    1175.00 !    2960.00 !      270 !        ! SMC_0402R_H016                   !                                 
R264                 !    4905.00 !    2025.00 !      180 !      m ! SMC_0402R_H016                   !                                 
R265                 !    4905.00 !    1975.00 !        0 !      m ! SMC_0402R_H016                   !                                 
R268                 !    4935.00 !    3525.00 !       90 !        ! SMC_0402R_H016                   !                                 
R269                 !    5010.00 !    3455.00 !      180 !      m ! SMC_0402R_H016                   !                                 
R349                 !    1360.00 !    3235.00 !      180 !      m ! SMC_0402R_H016                   !                                 
R248                 !    5750.00 !    2245.00 !        0 !        ! SMC_0402R_H016                   !                                 
R29                  !    1556.00 !    4141.00 !       90 !        ! SMC_0402R_H016                   !                                 
R35                  !    3443.00 !    3837.00 !      270 !        ! SMC_0402R_H016                   !                                 
R40                  !    3543.00 !    3833.00 !      180 !        ! SMC_0402R_H016                   !                                 
R254                 !    5675.00 !    2400.00 !        0 !        ! SMC_0402R_H016                   !                                 
R6                   !    1385.00 !    4105.00 !      270 !        ! SMC_0402R_H016                   !                                 
R17                  !    3623.00 !    3857.00 !       90 !        ! SMC_0402R_H016                   !                                 
R9                   !    5341.00 !    3902.00 !        0 !        ! SMC_0603R_H022                   !                                 
R252                 !    5700.00 !    2345.00 !       90 !      m ! SMC_0603R_H024                   !                                 
R50                  !    1445.00 !    4090.00 !      180 !      m ! SMC_0603R_H024                   !                                 
R54                  !    3543.00 !    3887.00 !        0 !      m ! SMC_0603R_H024                   !                                 
R253                 !    5720.00 !    1990.00 !      180 !      m ! SMC_0805R_H026                   !                                 
R33                  !    1840.00 !    4130.00 !      180 !      m ! SMC_0805R_H026                   !                                 
R39                  !    3185.00 !    3790.00 !       90 !      m ! SMC_0805R_H026                   !                                 
SP3                  !    5640.00 !    2170.00 !      270 !      m ! 0201_SOLDER_PREFORM_4MIL         !                                 
SP1                  !    1631.00 !    4031.00 !        0 !      m ! 0201_SOLDER_PREFORM_4MIL         !                                 
SP2                  !    3368.00 !    3947.00 !      180 !      m ! 0201_SOLDER_PREFORM_4MIL         !                                 
U12                  !    2690.00 !    2250.00 !      270 !      m ! SOT23_5                          !                                 
U26                  !    5575.00 !    2155.00 !        0 !        ! QFN18_138_P0197_V1               !                                 
U5                   !    1646.00 !    3966.00 !       90 !        ! QFN18_138_P0197_V1               !                                 
U6                   !    3353.00 !    4012.00 !      270 !        ! QFN18_138_P0197_V1               !                                 
U11                  !    3544.01 !    1915.49 !       90 !        ! QFN12_071_P0157                  !                                 
C47                  !    3636.73 !    2336.00 !      270 !        ! SMC_0201R                        !                                 
C51                  !    3636.73 !    2402.00 !       90 !        ! SMC_0201R                        !                                 
C312                 !     715.00 !    2423.00 !       90 !        ! SMC_0402R_H022                   !                                 
C313                 !     714.00 !    2273.00 !      270 !        ! SMC_0402R_H022                   !                                 
C273                 !    4635.00 !    3940.00 !        0 !      m ! SMC_0402R_H022                   !                                 
C285                 !    3180.00 !    2524.00 !      180 !        ! SMC_0402R_H022                   !                                 
C103                 !    4738.08 !    2000.91 !      180 !      m ! SMC_0402R_C_H022                 !                                 
C104                 !    3865.30 !    1745.00 !        0 !      m ! SMC_0402R_H022                   !                                 
C105                 !    4049.10 !    1626.90 !      270 !      m ! SMC_0402R_C_H022                 !                                 
C106                 !    4029.41 !    1804.06 !        0 !      m ! SMC_0402R_C_H022                 !                                 
C107                 !    4521.54 !    1823.75 !      270 !      m ! SMC_0402R_C_H022                 !                                 
C108                 !    4403.43 !    1351.30 !      270 !      m ! SMC_0402R_C_H022                 !                                 
C109                 !    4226.26 !    1685.95 !        0 !      m ! SMC_0402R_C_H022                 !                                 
C110                 !    3911.29 !    1489.10 !        0 !      m ! SMC_0402R_C_H022                 !                                 
C111                 !    4108.16 !    1607.21 !      180 !      m ! SMC_0402R_C_H022                 !                                 
C112                 !    4147.53 !    2040.28 !      180 !      m ! SMC_0402R_C_H022                 !                                 
C113                 !    4119.00 !    1750.00 !        0 !      m ! SMC_0402R_H022                   !                                 
C114                 !    4305.00 !    1670.00 !       90 !      m ! SMC_0402R_H022                   !                                 
C115                 !    4306.00 !    1816.00 !       90 !      m ! SMC_0402R_H022                   !                                 
C116                 !    3897.29 !    1293.61 !        0 !      m ! SMC_0402R_H022                   !                                 
C118                 !    4108.16 !    1567.84 !      180 !      m ! SMC_0402R_C_H022                 !                                 
C119                 !    4167.21 !    1981.23 !      270 !      m ! SMC_0402R_C_H022                 !                                 
C121                 !    4167.21 !    1587.52 !       90 !      m ! SMC_0402R_C_H022                 !                                 
C122                 !    4766.66 !    1408.36 !       90 !      m ! SMC_0402R_C_H022                 !                                 
C124                 !    4009.73 !    1469.41 !       90 !      m ! SMC_0402R_C_H022                 !                                 
C126                 !    4482.16 !    1941.85 !      270 !      m ! SMC_0402R_C_H022                 !                                 
C127                 !    4580.59 !    1410.35 !        0 !      m ! SMC_0402R_C_H022                 !                                 
C129                 !    4364.06 !    1626.90 !      270 !      m ! SMC_0402R_C_H022                 !                                 
C130                 !    4619.97 !    1961.54 !      180 !      m ! SMC_0402R_C_H022                 !                                 
C132                 !    4423.11 !    1922.17 !        0 !      m ! SMC_0402R_C_H022                 !                                 
C133                 !    4305.00 !    1570.00 !      270 !      m ! SMC_0402R_H022                   !                                 
C134                 !    4501.85 !    2079.65 !        0 !      m ! SMC_0402R_C_H022                 !                                 
C135                 !    4442.80 !    1430.04 !       90 !      m ! SMC_0402R_C_H022                 !                                 
C136                 !    3520.00 !    1355.00 !       90 !      m ! SMC_0402R_H022                   !                                 
C139                 !    4659.34 !    1804.06 !      180 !      m ! SMC_0402R_C_H022                 !                                 
C140                 !    3930.98 !    2099.33 !       90 !      m ! SMC_0402R_C_H022                 !                                 
C141                 !    4226.27 !    1567.84 !      180 !      m ! SMC_0402R_C_H022                 !                                 
C142                 !    4309.00 !    1465.00 !      270 !      m ! SMC_0402R_C_H022                 !                                 
C144                 !    4310.06 !    1917.49 !      270 !      m ! SMC_0402R_C_H022                 !                                 
C145                 !    4780.00 !    1842.11 !       90 !      m ! SMC_0402R_H022                   !                                 
C146                 !    4147.52 !    1489.10 !        0 !      m ! SMC_0402R_C_H022                 !                                 
C147                 !    4462.49 !    1646.58 !      180 !      m ! SMC_0402R_C_H022                 !                                 
C148                 !    3575.00 !    1600.00 !       90 !        ! SMC_0402R_H022                   !                                 
C149                 !    4300.00 !    2008.00 !      270 !      m ! SMC_0402R_H022                   !                                 
C150                 !    3630.00 !    2170.00 !      180 !      m ! SMC_0402R_H022                   !                                 
C151                 !    4659.33 !    1567.84 !        0 !      m ! SMC_0402R_C_H022                 !                                 
C152                 !    4482.17 !    1587.52 !       90 !      m ! SMC_0402R_C_H022                 !                                 
C153                 !    4108.15 !    1961.54 !        0 !      m ! SMC_0402R_C_H022                 !                                 
C156                 !    4167.21 !    1666.27 !      270 !      m ! SMC_0402R_C_H022                 !                                 
C157                 !    3950.66 !    2040.28 !        0 !      m ! SMC_0402R_C_H022                 !                                 
C161                 !    4442.80 !    1587.53 !      270 !      m ! SMC_0402R_C_H022                 !                                 
C162                 !    4245.95 !    2138.71 !      270 !      m ! SMC_0402R_C_H022                 !                                 
C165                 !    4534.11 !    1755.00 !      180 !      m ! SMC_0402R_H022                   !                                 
C166                 !    4245.95 !    1626.90 !      270 !      m ! SMC_0402R_C_H022                 !                                 
C169                 !    4206.58 !    1508.78 !       90 !      m ! SMC_0402R_C_H022                 !                                 
C171                 !    4403.43 !    1587.52 !       90 !      m ! SMC_0402R_C_H022                 !                                 
C178                 !    5390.00 !    1625.00 !       90 !      m ! SMC_0402R_H022                   !                                 
C199                 !    3582.00 !    2877.00 !       90 !        ! SMC_0402R_H022                   !                                 
C200                 !    4226.26 !    1804.06 !        0 !      m ! SMC_0402R_C_H022                 !                                 
C201                 !    4403.43 !    1666.26 !       90 !      m ! SMC_0402R_C_H022                 !                                 
C202                 !    4639.65 !    1863.12 !      270 !      m ! SMC_0402R_C_H022                 !                                 
C203                 !    3950.67 !    1843.43 !      180 !      m ! SMC_0402R_C_H022                 !                                 
C204                 !    4147.52 !    1528.47 !        0 !      m ! SMC_0402R_C_H022                 !                                 
C205                 !    3930.98 !    1745.01 !      270 !      m ! SMC_0402R_C_H022                 !                                 
C206                 !    4383.75 !    1804.06 !      180 !      m ! SMC_0402R_C_H022                 !                                 
C207                 !    4521.54 !    1666.26 !       90 !      m ! SMC_0402R_C_H022                 !                                 
C208                 !    4206.58 !    1430.04 !      270 !      m ! SMC_0402R_C_H022                 !                                 
C209                 !    3950.67 !    1646.58 !      180 !      m ! SMC_0402R_C_H022                 !                                 
C210                 !    4619.96 !    1685.95 !        0 !      m ! SMC_0402R_C_H022                 !                                 
C211                 !    3950.67 !    2000.91 !        0 !      m ! SMC_0402R_C_H022                 !                                 
C212                 !    4344.00 !    1741.00 !        0 !      m ! SMC_0402R_H022                   !                                 
C213                 !    4049.10 !    1390.67 !      270 !      m ! SMC_0402R_C_H022                 !                                 
C214                 !    4364.06 !    1548.15 !       90 !      m ! SMC_0402R_C_H022                 !                                 
C215                 !    4619.97 !    1922.17 !      180 !      m ! SMC_0402R_C_H022                 !                                 
C216                 !    3911.29 !    2158.39 !        0 !      m ! SMC_0402R_C_H022                 !                                 
C217                 !    3970.35 !    1469.42 !      270 !      m ! SMC_0402R_C_H022                 !                                 
C218                 !    4009.73 !    1548.16 !      270 !      m ! SMC_0402R_C_H022                 !                                 
C219                 !    4220.00 !    1750.00 !        0 !      m ! SMC_0402R_H022                   !                                 
C220                 !    4364.06 !    1469.42 !      270 !      m ! SMC_0402R_C_H022                 !                                 
C221                 !    4206.58 !    1863.12 !      270 !      m ! SMC_0402R_C_H022                 !                                 
C222                 !    4127.84 !    1666.26 !       90 !      m ! SMC_0402R_C_H022                 !                                 
C223                 !    4403.43 !    2178.08 !      270 !      m ! SMC_0402R_C_H022                 !                                 
C229                 !    4545.00 !    2845.00 !      180 !      m ! SMC_0402R_H022                   !                                 
C233                 !    4390.00 !    2720.00 !      270 !        ! SMC_0402R_H022                   !                                 
C235                 !    4545.00 !    2895.00 !        0 !        ! SMC_0402R_H022                   !                                 
C237                 !    4166.00 !    2792.00 !      180 !        ! SMC_0402R_H022                   !                                 
C251                 !    4414.00 !    1052.00 !       90 !        ! SMC_0402R_H022                   !                                 
C252                 !    4369.00 !    1052.00 !       90 !        ! SMC_0402R_H022                   !                                 
C253                 !    4055.00 !    1050.00 !       90 !        ! SMC_0402R_H022                   !                                 
C254                 !    4010.00 !    1050.00 !       90 !        ! SMC_0402R_H022                   !                                 
C256                 !    5555.00 !    2345.00 !       90 !        ! SMC_0402R_H022                   !                                 
C268                 !    5410.00 !    1815.00 !       90 !        ! SMC_0402R_H022                   !                                 
C17                  !    1548.00 !     642.20 !       90 !        ! SMC_0402R_H022                   !                                 
C18                  !    3255.00 !    3685.00 !       90 !        ! SMC_0402R_H022                   !                                 
C29                  !    1456.00 !    3946.00 !      180 !        ! SMC_0402R_H022                   !                                 
C36                  !    3023.03 !     605.00 !      270 !      m ! SMC_0402R_H022                   !                                 
C37                  !    2976.20 !     667.80 !        0 !        ! SMC_0402R_H022                   !                                 
C38                  !    2916.00 !    3206.00 !      180 !        ! SMC_0402R_H022                   !                                 
C46                  !    3543.00 !    4032.00 !        0 !        ! SMC_0402R_H022                   !                                 
C67                  !    3505.00 !    1810.00 !       90 !      m ! SMC_0402R_H022                   !                                 
C19                  !    2343.10 !     604.90 !      270 !      m ! SMC_0402R_H022                   !                                 
C23                  !    2393.11 !     605.00 !      270 !      m ! SMC_0402R_H022                   !                                 
C24                  !    2461.22 !     605.00 !      270 !      m ! SMC_0402R_H022                   !                                 
C25                  !    2511.22 !     605.00 !      270 !      m ! SMC_0402R_H022                   !                                 
C26                  !    2658.07 !     605.00 !      270 !      m ! SMC_0402R_H022                   !                                 
C27                  !    2708.07 !     605.00 !      270 !      m ! SMC_0402R_H022                   !                                 
C28                  !    2800.55 !     605.00 !      270 !      m ! SMC_0402R_H022                   !                                 
C34                  !    2850.55 !     605.00 !      270 !      m ! SMC_0402R_H022                   !                                 
C35                  !    2973.03 !     605.00 !      270 !      m ! SMC_0402R_H022                   !                                 
C12                  !    2176.00 !    3866.00 !      270 !        ! SMC_0402R_H022                   !                                 
C80                  !    4635.00 !    3895.00 !        0 !      m ! SMC_0402R_H022                   !                                 
C81                  !    4530.00 !    3870.00 !       90 !        ! SMC_0402R_H022                   !                                 
C82                  !     656.00 !     615.00 !      180 !      m ! SMC_0402R_H022                   !                                 
C83                  !     625.00 !    1105.00 !      270 !        ! SMC_0402R_H022                   !                                 
C84                  !     606.00 !    1668.45 !      270 !        ! SMC_0402R_H022                   !                                 
C85                  !     640.00 !    2250.00 !      270 !        ! SMC_0402R_H022                   !                                 
C250                 !    3705.00 !    2405.00 !      270 !        ! SMC_0402R_H022                   !                                 
C69                  !    2590.00 !    2285.00 !       90 !      m ! SMC_0402R_H022                   !                                 
C70                  !    2790.00 !    2317.00 !       90 !      m ! SMC_0402R_H022                   !                                 
C88                  !    1630.00 !    3525.00 !       90 !      m ! SMC_0402R_H022                   !                                 
C89                  !    4405.00 !    3790.00 !        0 !        ! SMC_0402R_H022                   !                                 
C94                  !     700.00 !    3405.00 !       90 !      m ! SMC_0402R_H022                   !                                 
C97                  !    4530.00 !    3270.00 !        0 !        ! SMC_0402R_H022                   !                                 
C101                 !    1265.00 !    3585.00 !      270 !      m ! SMC_0402R_H022                   !                                 
C102                 !    4170.00 !    3450.00 !      270 !      m ! SMC_0402R_H022                   !                                 
C123                 !    3980.00 !    3450.00 !      270 !      m ! SMC_0402R_H022                   !                                 
C298                 !    1840.00 !    3190.00 !        0 !        ! SMC_0402R_H022                   !                                 
C302                 !    1885.00 !    2960.00 !       90 !        ! SMC_0402R_H022                   !                                 
C304                 !    1845.00 !    3040.00 !        0 !        ! SMC_0402R_H022                   !                                 
C309                 !    1510.00 !    3185.00 !       90 !        ! SMC_0402R_H022                   !                                 
C315                 !    4375.00 !    3965.00 !      180 !      m ! SMC_0402R_H022                   !                                 
C316                 !    4240.00 !    3962.00 !      270 !      m ! SMC_0402R_H022                   !                                 
C288                 !    2150.00 !     615.00 !       90 !        ! SMC_0402R_H022                   !                                 
C290                 !    2200.00 !     635.00 !      270 !      m ! SMC_0402R_H022                   !                                 
C305                 !    6400.00 !    1135.00 !      180 !        ! SMC_0402R_H022                   !                                 
C306                 !    2218.00 !    2952.00 !       90 !        ! SMC_0402R_H022                   !                                 
C1                   !     860.00 !     812.00 !      270 !      m ! SMC_0402R_H022                   !                                 
C59                  !    2855.00 !    2865.00 !      270 !      m ! SMC_0402R_H022                   !                                 
C60                  !    2900.00 !    2865.00 !      270 !      m ! SMC_0402R_H022                   !                                 
C62                  !    3245.00 !    2880.00 !       90 !      m ! SMC_0402R_H022                   !                                 
C63                  !    6289.00 !    1991.74 !      270 !        ! SMC_0402R_H022                   !                                 
C65                  !    3020.00 !    2005.00 !      180 !      m ! SMC_0402R_H022                   !                                 
C66                  !    3020.00 !    2050.00 !      180 !      m ! SMC_0402R_H022                   !                                 
C68                  !    2440.00 !    2355.00 !        0 !      m ! SMC_0402R_H022                   !                                 
C71                  !    2790.00 !    2185.00 !      270 !      m ! SMC_0402R_H022                   !                                 
C73                  !    5085.00 !    3875.00 !       90 !      m ! SMC_0402R_H022                   !                                 
C78                  !    5035.00 !    3875.00 !       90 !      m ! SMC_0402R_H022                   !                                 
C92                  !    5270.00 !     920.00 !        0 !        ! SMC_0402R_H022                   !                                 
C272                 !    5110.00 !    3775.00 !      180 !        ! SMC_0402R_H022                   !                                 
C3                   !    5741.00 !    3567.00 !        0 !        ! SMC_0402R_H022                   !                                 
C5                   !    5741.00 !    3807.00 !        0 !        ! SMC_0402R_H022                   !                                 
C7                   !    5741.00 !    3857.00 !        0 !        ! SMC_0402R_H022                   !                                 
C96                  !    1355.00 !    3500.00 !      180 !      m ! SMC_0402R_H022                   !                                 
C100                 !    1130.00 !    3585.00 !      270 !      m ! SMC_0402R_H022                   !                                 
C275                 !    6050.00 !    2270.00 !        0 !        ! SMC_0402R_H022                   !                                 
C276                 !     928.00 !    2580.48 !      180 !        ! SMC_0402R_H022                   !                                 
C278                 !     929.48 !    2683.00 !        0 !        ! SMC_0402R_H022                   !                                 
C279                 !    3546.00 !    2534.00 !      270 !        ! SMC_0402R_H022                   !                                 
C281                 !    3435.00 !    2532.00 !       90 !        ! SMC_0402R_H022                   !                                 
C95                  !    1175.00 !    3475.00 !      180 !      m ! SMC_0402R_H022                   !                                 
C182                 !    3662.00 !    2997.00 !      270 !        ! SMC_0402R_H022                   !                                 
C183                 !    5035.00 !    2474.00 !        0 !        ! SMC_0402R_H022                   !                                 
C184                 !    3912.00 !    3092.00 !        0 !        ! SMC_0402R_H022                   !                                 
C187                 !    4961.00 !    2707.00 !       90 !        ! SMC_0402R_H022                   !                                 
C188                 !    3797.00 !    2990.00 !      270 !        ! SMC_0402R_H022                   !                                 
C189                 !    5063.00 !    2597.00 !        0 !        ! SMC_0402R_H022                   !                                 
C196                 !    3797.00 !    2870.00 !       90 !        ! SMC_0402R_H022                   !                                 
C197                 !    5183.00 !    2592.00 !      180 !        ! SMC_0402R_H022                   !                                 
C226                 !    5640.00 !     965.00 !      270 !        ! SMC_0402R_H022                   !                                 
C227                 !    5772.00 !     679.00 !      270 !        ! SMC_0402R_H022                   !                                 
C230                 !    5670.00 !     792.00 !      180 !        ! SMC_0402R_H022                   !                                 
C236                 !    4545.00 !    2945.00 !        0 !        ! SMC_0402R_H022                   !                                 
C242                 !    5548.00 !     792.00 !        0 !        ! SMC_0402R_H022                   !                                 
C244                 !    4290.00 !     730.00 !      180 !      m ! SMC_0402R_H022                   !                                 
C245                 !    3770.00 !     790.00 !       90 !      m ! SMC_0402R_H022                   !                                 
C248                 !    4320.00 !     940.00 !      270 !      m ! SMC_0402R_H022                   !                                 
C249                 !    3890.00 !     970.00 !        0 !        ! SMC_0402R_H022                   !                                 
C255                 !    5331.00 !    2259.00 !      270 !        ! SMC_0402R_H022                   !                                 
C261                 !    5450.00 !    2110.00 !      270 !        ! SMC_0402R_H022                   !                                 
C262                 !    5700.00 !    2130.00 !      270 !        ! SMC_0402R_H022                   !                                 
C265                 !    5510.00 !    2045.00 !       90 !      m ! SMC_0402R_H022                   !                                 
C2                   !    5616.00 !    3569.00 !        0 !        ! SMC_0402R_H022                   !                                 
C33                  !    1671.00 !    4091.00 !        0 !        ! SMC_0402R_H022                   !                                 
C39                  !     220.00 !    3075.00 !      180 !      m ! SMC_0402R_H022                   !                                 
C40                  !    6141.00 !    2299.00 !      270 !        ! SMC_0402R_H022                   !                                 
C41                  !    1691.00 !    3841.00 !        0 !        ! SMC_0402R_H022                   !                                 
C44                  !    1745.00 !    3910.00 !      180 !      m ! SMC_0402R_H022                   !                                 
C52                  !    3328.00 !    3887.00 !      180 !        ! SMC_0402R_H022                   !                                 
C53                  !    3308.00 !    4137.00 !      180 !        ! SMC_0402R_H022                   !                                 
C56                  !    3265.00 !    4070.00 !        0 !      m ! SMC_0402R_H022                   !                                 
C74                  !    1445.00 !    3725.00 !      270 !        ! SMC_0402R_H022                   !                                 
C76                  !    3573.00 !    4197.00 !        0 !        ! SMC_0402R_H022                   !                                 
C225                 !    1194.70 !     613.60 !        0 !        ! SMC_0402R_H022                   !                                 
C308                 !    1460.00 !    3040.00 !      270 !        ! SMC_0805R_H057                   !                                 
C297                 !    5498.00 !    3364.00 !        0 !      m ! SMC_0805R_H057                   !                                 
C299                 !    5498.00 !    3288.00 !        0 !      m ! SMC_0805R_H057                   !                                 
C300                 !    1855.00 !    3105.00 !        0 !        ! SMC_0805R_H057                   !                                 
C301                 !    5498.00 !    3441.00 !        0 !      m ! SMC_0805R_H057                   !                                 
C303                 !    5494.00 !    3206.00 !        0 !      m ! SMC_0805R_H057                   !                                 
C282                 !    3035.00 !    2880.00 !      270 !      m ! SMC_0805R_H057                   !                                 
C283                 !    3110.00 !    2880.00 !      270 !      m ! SMC_0805R_H057                   !                                 
C6                   !    5331.00 !    3827.00 !      180 !        ! SMC_0805R_H057                   !                                 
C9                   !    5336.00 !    3705.00 !       90 !        ! SMC_0805R_H057                   !                                 
C10                  !    5254.00 !    3705.00 !       90 !        ! SMC_0805R_H057                   !                                 
C185                 !    3732.00 !    2985.00 !      270 !        ! SMC_0805R_H057                   !                                 
C186                 !    5047.00 !    2534.00 !        0 !        ! SMC_0805R_H057                   !                                 
C194                 !    3729.00 !    2837.00 !       90 !        ! SMC_0805R_H057                   !                                 
C195                 !    5195.00 !    2521.00 !      180 !        ! SMC_0805R_H057                   !                                 
C228                 !    5665.00 !     859.00 !      180 !        ! SMC_0805R_H057                   !                                 
C239                 !    5517.00 !     863.00 !        0 !        ! SMC_0805R_H057                   !                                 
C257                 !    5760.00 !    2120.00 !      270 !        ! SMC_0805R_H057                   !                                 
C260                 !    5385.00 !    2090.00 !      270 !        ! SMC_0805R_H057                   !                                 
C30                  !    1681.00 !    4151.00 !        0 !        ! SMC_0805R_H057                   !                                 
C32                  !    1711.00 !    3776.00 !        0 !        ! SMC_0805R_H057                   !                                 
C48                  !    3318.00 !    3827.00 !      180 !        ! SMC_0805R_H057                   !                                 
C50                  !    3288.00 !    4202.00 !      180 !        ! SMC_0805R_H057                   !                                 
C58                  !    2960.00 !    2880.00 !      270 !      m ! SMC_0805R_H057                   !                                 
C61                  !    6225.00 !    2003.74 !      270 !        ! SMC_0805R_H057                   !                                 
C64                  !    3035.00 !    1945.00 !      180 !      m ! SMC_0805R_H057                   !                                 
C72                  !    5050.00 !    3870.00 !      270 !        ! SMC_0805R_H057                   !                                 
C79                  !    4621.00 !    3927.00 !      180 !        ! SMC_0805R_H057                   !                                 
U9                   !    6269.89 !    2258.34 !      270 !        ! SOT23_6                          !                                 
U17                  !     720.00 !    3450.00 !       90 !        ! SOT23_6                          !                                 
GF1                  !    1797.24 !     137.81 !        0 !        ! S_M_EF64_PCIE_P0394_V1           !                                 
J18                  !     804.00 !    2091.00 !      180 !        ! S_M_H_3P_S_P058                  !                                 
J11                  !    6453.81 !    2110.24 !       90 !        ! S_F_USB_1X5_G2_GH4_RA_P0256      !                                 
CR6                  !    5708.00 !    2966.00 !      270 !      m ! SOT143                           !                                 
CR7                  !    5713.00 !    2681.00 !      270 !      m ! SOT143                           !                                 
CR4                  !     235.00 !    2140.00 !       90 !        ! SOT143                           !                                 
CR5                  !     235.00 !    1000.00 !       90 !        ! SOT143                           !                                 
J10                  !    6121.00 !    2815.00 !       90 !        ! S_M_DIL_2X5_P100_V1              !                                 
J14                  !    5608.00 !    2821.00 !       90 !        ! S_M_DIL_2X5_P100_V1              !                                 
DS12                 !    6143.70 !    4108.27 !      270 !        ! SMC_DS_063X031_V4                !                                 
DS19                 !    5907.48 !    4108.27 !      270 !        ! SMC_DS_063X031_V4                !                                 
DS20                 !    6025.59 !    4108.27 !      270 !        ! SMC_DS_063X031_V4                !                                 
DS10                 !    6025.59 !    4246.06 !      270 !        ! SMC_DS_063X031_V4                !                                 
DS11                 !    6143.70 !    4246.06 !      270 !        ! SMC_DS_063X031_V4                !                                 
DS5                  !    5789.37 !    4108.27 !      270 !        ! SMC_DS_063X031_V4                !                                 
DS6                  !    5435.04 !    4108.27 !      270 !        ! SMC_DS_063X031_V4                !                                 
DS7                  !    5553.15 !    4108.27 !      270 !        ! SMC_DS_063X031_V4                !                                 
DS8                  !    5671.26 !    4108.27 !      270 !        ! SMC_DS_063X031_V4                !                                 
DS9                  !    5283.00 !    4180.01 !      270 !        ! SMC_DS_063X031_V4                !                                 
DS1                  !    5435.04 !    4246.06 !      270 !        ! SMC_DS_063X031_V4                !                                 
DS2                  !    5553.15 !    4246.06 !      270 !        ! SMC_DS_063X031_V4                !                                 
DS3                  !    5671.26 !    4246.06 !      270 !        ! SMC_DS_063X031_V4                !                                 
DS4                  !    5789.37 !    4246.06 !      270 !        ! SMC_DS_063X031_V4                !                                 
U4                   !    3162.00 !    3315.00 !      180 !        ! SOP16_173_P0256_H043             !                                 
R492                 !     530.00 !    1465.00 !       90 !      m ! SMC_0402R_H016                   !                                 
R493                 !     535.00 !     905.00 !       90 !      m ! SMC_0402R_H016                   !                                 
R494                 !     530.00 !    2605.00 !       90 !      m ! SMC_0402R_H016                   !                                 
R495                 !     530.00 !    2070.00 !       90 !      m ! SMC_0402R_H016                   !                                 
R135                 !    5525.00 !    2770.00 !        0 !      m ! SMC_0402R_H016                   !                                 
R310                 !    2916.00 !    3259.00 !        0 !        ! SMC_0402R_H016                   !                                 
R311                 !    2917.00 !    3332.00 !        0 !        ! SMC_0402R_H016                   !                                 
R312                 !    1329.50 !     658.00 !      180 !        ! SMC_0402R_H016                   !                                 
R313                 !    1329.70 !     753.00 !      180 !        ! SMC_0402R_H016                   !                                 
R471                 !     725.00 !    3245.00 !      180 !        ! SMC_0402R_H016                   !                                 
R472                 !     725.00 !    3200.00 !      180 !        ! SMC_0402R_H016                   !                                 
R473                 !     725.00 !    3155.00 !        0 !      m ! SMC_0402R_H016                   !                                 
R31                  !    1645.00 !    3885.00 !      180 !      m ! SMC_0402R_H016                   !                                 
R37                  !    3365.00 !    4095.00 !        0 !      m ! SMC_0402R_H016                   !                                 
R61                  !    3047.00 !    3210.00 !      180 !      m ! SMC_0402R_H016                   !                                 
R62                  !    3047.00 !    3260.00 !      180 !      m ! SMC_0402R_H016                   !                                 
R92                  !    4905.00 !    1855.00 !        0 !      m ! SMC_0402R_H016                   !                                 
R128                 !    1155.00 !    3710.00 !      270 !        ! SMC_0402R_H016                   !                                 
R129                 !    1105.00 !    3710.00 !      270 !        ! SMC_0402R_H016                   !                                 
R250                 !    5510.00 !    2150.00 !       90 !      m ! SMC_0402R_H016                   !                                 
R343                 !     858.00 !    2810.00 !      270 !      m ! SMC_0402R_H016                   !                                 
R346                 !     640.00 !    2790.00 !      180 !        ! SMC_0402R_H016                   !                                 
R347                 !     663.48 !    2614.00 !      180 !        ! SMC_0402R_H016                   !                                 
R350                 !     769.48 !    2546.00 !      270 !        ! SMC_0402R_H016                   !                                 
R351                 !     835.00 !    2545.00 !      270 !        ! SMC_0402R_H016                   !                                 
R356                 !    4905.00 !    2070.00 !      180 !        ! SMC_0402R_H016                   !                                 
R464                 !    3870.00 !    3445.00 !       90 !        ! SMC_0402R_H016                   !                                 
R465                 !    4080.00 !    3450.00 !       90 !        ! SMC_0402R_H016                   !                                 
R315                 !     760.00 !    2423.00 !       90 !      m ! SMC_0402R_H016                   !                                 
R316                 !     805.00 !    2423.00 !       90 !      m ! SMC_0402R_H016                   !                                 
R324                 !    4375.00 !    3915.00 !      180 !        ! SMC_0402R_H016                   !                                 
R140                 !    3814.00 !    3092.00 !        0 !        ! SMC_0402R_H016                   !                                 
R141                 !    4889.00 !    2707.00 !      270 !        ! SMC_0402R_H016                   !                                 
R181                 !    3947.00 !    2725.00 !        0 !        ! SMC_0402R_H016                   !                                 
R182                 !    5315.00 !    2790.00 !       90 !        ! SMC_0402R_H016                   !                                 
R230                 !    5425.00 !     640.00 !        0 !      m ! SMC_0402R_H016                   !                                 
R244                 !    5510.00 !    2345.00 !       90 !      m ! SMC_0402R_H016                   !                                 
R245                 !    5465.00 !    2345.00 !      270 !        ! SMC_0402R_H016                   !                                 
R263                 !    3573.00 !    4197.00 !      180 !      m ! SMC_0402R_H016                   !                                 
R7                   !    5741.00 !    3617.00 !      180 !        ! SMC_0402R_H016                   !                                 
R8                   !    5741.00 !    3667.00 !      180 !        ! SMC_0402R_H016                   !                                 
R22                  !    2511.22 !     605.00 !      270 !        ! SMC_0402R_H016                   !                                 
R23                  !    1864.60 !     623.20 !      270 !      m ! SMC_0402R_H016                   !                                 
R28                  !    5525.00 !    2595.00 !        0 !      m ! SMC_0402R_H016                   !                                 
R43                  !    5475.00 !    2870.00 !      180 !      m ! SMC_0402R_H016                   !                                 
R83                  !    3189.00 !    2110.00 !      180 !        ! SMC_0402R_H016                   !                                 
R84                  !    3189.00 !    2060.00 !      180 !        ! SMC_0402R_H016                   !                                 
R97                  !    3140.00 !    1895.00 !        0 !        ! SMC_0402R_H016                   !                                 
R98                  !    3140.00 !    1850.00 !        0 !        ! SMC_0402R_H016                   !                                 
R105                 !    3554.00 !    1931.49 !      180 !      m ! SMC_0402R_H016                   !                                 
R106                 !    3554.00 !    1886.49 !      180 !      m ! SMC_0402R_H016                   !                                 
R41                  !    5525.00 !    3065.00 !        0 !      m ! SMC_0402R_H016                   !                                 
R42                  !    5525.00 !    2815.00 !        0 !      m ! SMC_0402R_H016                   !                                 
R85                  !    3189.00 !    2015.00 !      180 !        ! SMC_0402R_H016                   !                                 
R86                  !    3189.00 !    1965.00 !      180 !        ! SMC_0402R_H016                   !                                 
R87                  !    3144.00 !    1800.00 !      180 !        ! SMC_0402R_H016                   !                                 
R88                  !    3144.00 !    1750.00 !      180 !        ! SMC_0402R_H016                   !                                 
R120                 !     530.00 !    2605.00 !      270 !        ! SMC_0402R_H016                   !                                 
R121                 !     530.00 !    2070.00 !      270 !        ! SMC_0402R_H016                   !                                 
R156                 !     530.00 !    1465.00 !      270 !        ! SMC_0402R_H016                   !                                 
R157                 !     535.00 !     905.00 !      270 !        ! SMC_0402R_H016                   !                                 
R125                 !     371.00 !    1547.98 !       90 !        ! SMC_0402R_H016                   !                                 
R272                 !     281.00 !    1547.98 !       90 !        ! SMC_0402R_H016                   !                                 
R274                 !     800.00 !    1250.00 !      180 !        ! SMC_0402R_H016                   !                                 
R352                 !    1125.00 !    2960.00 !      270 !        ! SMC_0402R_H016                   !                                 
R353                 !    1075.00 !    2960.00 !      270 !        ! SMC_0402R_H016                   !                                 
R373                 !     800.00 !    1150.00 !      180 !        ! SMC_0402R_H016                   !                                 
R375                 !     422.00 !    2685.08 !       90 !        ! SMC_0402R_H016                   !                                 
R376                 !     287.00 !    2685.08 !       90 !        ! SMC_0402R_H016                   !                                 
R401                 !     766.47 !    1975.00 !      180 !        ! SMC_0402R_H016                   !                                 
R424                 !     766.47 !    1840.00 !      180 !        ! SMC_0402R_H016                   !                                 
R426                 !     380.00 !    3210.00 !       90 !        ! SMC_0402R_H016                   !                                 
R427                 !     280.00 !    3210.00 !       90 !        ! SMC_0402R_H016                   !                                 
R443                 !    4340.00 !    3475.00 !      270 !        ! SMC_0402R_H016                   !                                 
R456                 !    1055.00 !    3710.00 !      270 !        ! SMC_0402R_H016                   !                                 
R124                 !     236.00 !    1547.98 !       90 !        ! SMC_0402R_H016                   !                                 
R273                 !     800.00 !    1100.00 !      180 !        ! SMC_0402R_H016                   !                                 
R374                 !     242.00 !    2685.08 !       90 !        ! SMC_0402R_H016                   !                                 
R400                 !     766.47 !    1795.00 !      180 !        ! SMC_0402R_H016                   !                                 
R425                 !     230.00 !    3210.00 !       90 !        ! SMC_0402R_H016                   !                                 
R131                 !    1280.00 !    3115.00 !       90 !      m ! SMC_0402R_H016                   !                                 
R132                 !    1360.00 !    3280.00 !      180 !      m ! SMC_0402R_H016                   !                                 
R275                 !    4619.96 !    1292.24 !      180 !      m ! SMC_0402R_C_H016                 !                                 
R276                 !    3259.00 !    1990.00 !      270 !        ! SMC_0402R_H016                   !                                 
R277                 !    3259.00 !    2085.00 !      270 !        ! SMC_0402R_H016                   !                                 
R278                 !    4501.86 !    1449.73 !      180 !      m ! SMC_0402R_C_H016                 !                                 
R108                 !    5550.00 !    4115.00 !      180 !      m ! SMC_0402R_H016                   !                                 
R196                 !    3725.00 !    1720.00 !      180 !      m ! SMC_0402R_H016                   !                                 
R197                 !    4068.78 !    1489.10 !        0 !      m ! SMC_0402R_C_H016                 !                                 
R198                 !    4068.78 !    1685.95 !        0 !      m ! SMC_0402R_C_H016                 !                                 
R211                 !    4905.00 !    1765.00 !      180 !        ! SMC_0402R_H016                   !                                 
R212                 !    4905.00 !    1720.00 !        0 !        ! SMC_0402R_H016                   !                                 
R217                 !    4905.00 !    1630.00 !        0 !      m ! SMC_0402R_H016                   !                                 
R218                 !    4905.00 !    1675.00 !      180 !      m ! SMC_0402R_H016                   !                                 
R221                 !    4980.00 !    1385.00 !      180 !        ! SMC_0402R_H016                   !                                 
R222                 !    4980.00 !    1430.00 !        0 !        ! SMC_0402R_H016                   !                                 
R142                 !    1456.00 !    3901.00 !      180 !      m ! SMC_0402R_H016                   !                                 
R89                  !    2817.50 !    1945.00 !      180 !      m ! SMC_0402R_H016                   !                                 
R90                  !    2795.00 !    1859.00 !      270 !      m ! SMC_0402R_H016                   !                                 
R451                 !    3860.00 !    3758.00 !        0 !      m ! SMC_0402R_H016                   !                                 
R453                 !    4405.00 !    3745.00 !        0 !        ! SMC_0402R_H016                   !                                 
R458                 !    3994.00 !    3239.00 !      180 !      m ! SMC_0402R_H016                   !                                 
R459                 !    4533.00 !    3220.00 !      180 !        ! SMC_0402R_H016                   !                                 
R460                 !    1040.00 !    3585.00 !       90 !      m ! SMC_0402R_H016                   !                                 
R483                 !    4715.00 !     915.00 !      180 !      m ! SMC_0402R_H016                   !                                 
R484                 !    5270.00 !     870.00 !      180 !        ! SMC_0402R_H016                   !                                 
R409                 !    2083.00 !    2952.00 !       90 !      m ! SMC_0402R_H016                   !                                 
R411                 !    6400.00 !     965.00 !      180 !      m ! SMC_0402R_H016                   !                                 
R413                 !    2128.00 !    2952.00 !       90 !      m ! SMC_0402R_H016                   !                                 
R415                 !    6400.00 !    1020.00 !      180 !      m ! SMC_0402R_H016                   !                                 
R416                 !    2173.00 !    2952.00 !       90 !      m ! SMC_0402R_H016                   !                                 
R417                 !    6400.00 !    1080.00 !      180 !      m ! SMC_0402R_H016                   !                                 
R101                 !    6300.00 !    1988.74 !       90 !      m ! SMC_0402R_H016                   !                                 
R102                 !    6255.00 !    1988.74 !      270 !      m ! SMC_0402R_H016                   !                                 
R103                 !    6210.00 !    1988.74 !       90 !      m ! SMC_0402R_H016                   !                                 
R302                 !    3180.00 !    2164.00 !      180 !        ! SMC_0402R_H016                   !                                 
R303                 !    3285.00 !    2532.00 !       90 !        ! SMC_0402R_H016                   !                                 
R305                 !    3180.00 !    2569.00 !      180 !        ! SMC_0402R_H016                   !                                 
R307                 !    3180.00 !    2479.00 !      180 !        ! SMC_0402R_H016                   !                                 
R180                 !    5675.00 !    4105.00 !       90 !      m ! SMC_0402R_H016                   !                                 
R214                 !    4440.00 !    2440.00 !       90 !        ! SMC_0402R_H016                   !                                 
R216                 !    4485.00 !    2440.00 !      270 !      m ! SMC_0402R_H016                   !                                 
R220                 !    4440.00 !    2440.00 !      270 !      m ! SMC_0402R_H016                   !                                 
R223                 !    4575.00 !    2440.00 !      270 !      m ! SMC_0402R_H016                   !                                 
R224                 !    4620.00 !    2440.00 !       90 !      m ! SMC_0402R_H016                   !                                 
R256                 !    5790.00 !    4120.00 !      180 !      m ! SMC_0402R_H016                   !                                 
R260                 !    4545.00 !    2795.00 !        0 !      m ! SMC_0402R_H016                   !                                 
R262                 !    5790.00 !    4075.00 !        0 !      m ! SMC_0402R_H016                   !                                 
R69                  !    5969.02 !    1929.65 !       90 !      m ! SMC_0402R_H016                   !                                 
R334                 !     290.00 !    2850.00 !       90 !      m ! SMC_0402R_H016                   !                                 
R336                 !     220.00 !    2875.00 !        0 !      m ! SMC_0402R_H016                   !                                 
R338                 !     220.00 !    3025.00 !        0 !      m ! SMC_0402R_H016                   !                                 
R364                 !    4375.00 !    4065.00 !      180 !        ! SMC_0402R_H016                   !                                 
R366                 !    4375.00 !    4115.00 !      180 !        ! SMC_0402R_H016                   !                                 
R234                 !    4485.00 !    2440.00 !       90 !        ! SMC_0402R_H016                   !                                 
R238                 !    4535.00 !    2345.00 !       90 !        ! SMC_0402R_H016                   !                                 
R339                 !    4530.00 !    2440.00 !       90 !        ! SMC_0402R_H016                   !                                 
R348                 !    4620.00 !    2440.00 !       90 !        ! SMC_0402R_H016                   !                                 
R362                 !    4650.00 !    2320.00 !       90 !        ! SMC_0402R_H016                   !                                 
R26                  !     829.00 !    1594.00 !        0 !      m ! SMC_0402R_H016                   !                                 
R27                  !     825.00 !    1500.00 !        0 !      m ! SMC_0402R_H016                   !                                 
R45                  !     721.00 !     838.00 !       90 !      m ! SMC_0402R_H016                   !                                 
R58                  !     829.00 !    1684.00 !        0 !      m ! SMC_0402R_H016                   !                                 
R59                  !     695.00 !    1495.00 !      180 !      m ! SMC_0402R_H016                   !                                 
R60                  !    3277.00 !    3475.00 !      180 !      m ! SMC_0402R_H016                   !                                 
R66                  !    5919.02 !    1929.65 !       90 !        ! SMC_0402R_H016                   !                                 
R67                  !    6069.02 !    1929.65 !       90 !        ! SMC_0402R_H016                   !                                 
R72                  !     663.48 !    2664.00 !        0 !        ! SMC_0402R_H016                   !                                 
R73                  !     735.00 !    2790.00 !      180 !        ! SMC_0402R_H016                   !                                 
R76                  !    3440.00 !    2210.00 !        0 !      m ! SMC_0402R_H016                   !                                 
R77                  !    3350.00 !    2210.00 !      180 !      m ! SMC_0402R_H016                   !                                 
R78                  !    3180.00 !    2299.00 !      180 !        ! SMC_0402R_H016                   !                                 
R79                  !    3180.00 !    2254.00 !        0 !        ! SMC_0402R_H016                   !                                 
R80                  !    3335.00 !    2532.00 !       90 !      m ! SMC_0402R_H016                   !                                 
R81                  !    6015.00 !    2615.00 !        0 !      m ! SMC_0402R_H016                   !                                 
R82                  !    6015.00 !    2790.00 !        0 !      m ! SMC_0402R_H016                   !                                 
R91                  !     908.00 !    2810.00 !       90 !      m ! SMC_0402R_H016                   !                                 
R93                  !    4905.00 !    1630.00 !      180 !        ! SMC_0402R_H016                   !                                 
R94                  !    4905.00 !    1975.00 !      180 !        ! SMC_0402R_H016                   !                                 
R95                  !    4905.00 !    2025.00 !      180 !        ! SMC_0402R_H016                   !                                 
R96                  !    3145.00 !    1695.00 !        0 !        ! SMC_0402R_H016                   !                                 
R100                 !    2540.00 !    2285.00 !      270 !      m ! SMC_0402R_H016                   !                                 
R109                 !    4985.00 !    3525.00 !      270 !      m ! SMC_0402R_H016                   !                                 
R110                 !    4935.00 !    3525.00 !      270 !      m ! SMC_0402R_H016                   !                                 
R111                 !    4885.00 !    3525.00 !      270 !      m ! SMC_0402R_H016                   !                                 
R112                 !    4985.00 !    3525.00 !       90 !        ! SMC_0402R_H016                   !                                 
R113                 !    4885.00 !    3525.00 !       90 !        ! SMC_0402R_H016                   !                                 
R116                 !    4785.00 !    3525.00 !      270 !        ! SMC_0402R_H016                   !                                 
R117                 !    4835.00 !    3525.00 !      270 !        ! SMC_0402R_H016                   !                                 
R133                 !    5523.00 !    2721.00 !        0 !      m ! SMC_0402R_H016                   !                                 
R134                 !    5525.00 !    2640.00 !        0 !      m ! SMC_0402R_H016                   !                                 
R136                 !    5523.00 !    2922.50 !        0 !      m ! SMC_0402R_H016                   !                                 
R137                 !    5525.00 !    3020.00 !        0 !      m ! SMC_0402R_H016                   !                                 
R143                 !    4545.00 !    2995.00 !      180 !        ! SMC_0402R_H016                   !                                 
R144                 !     697.00 !    1599.00 !      180 !      m ! SMC_0402R_H016                   !                                 
R145                 !     696.00 !    1544.00 !      180 !      m ! SMC_0402R_H016                   !                                 
R175                 !    1329.50 !     658.00 !        0 !      m ! SMC_0402R_H016                   !                                 
R176                 !    1329.70 !     708.00 !        0 !      m ! SMC_0402R_H016                   !                                 
R183                 !    1329.50 !     613.00 !      180 !        ! SMC_0402R_H016                   !                                 
R184                 !    1329.70 !     708.00 !      180 !        ! SMC_0402R_H016                   !                                 
R266                 !    3554.00 !    1766.49 !       90 !        ! SMC_0402R_H016                   !                                 
R267                 !    2620.00 !    2375.00 !        0 !      m ! SMC_0402R_H016                   !                                 
R294                 !    1446.00 !    3851.00 !      180 !        ! SMC_0402R_H016                   !                                 
R298                 !    5920.53 !    2330.00 !      180 !        ! SMC_0402R_H016                   !                                 
R299                 !    6019.02 !    1929.65 !      270 !        ! SMC_0402R_H016                   !                                 
R319                 !    4375.00 !    3865.00 !        0 !      m ! SMC_0402R_H016                   !                                 
R321                 !    4375.00 !    4065.00 !        0 !      m ! SMC_0402R_H016                   !                                 
R322                 !    4375.00 !    4115.00 !        0 !      m ! SMC_0402R_H016                   !                                 
R329                 !    6170.00 !    1455.00 !      270 !      m ! SMC_0402R_H016                   !                                 
R330                 !    3440.00 !    2885.00 !       90 !      m ! SMC_0402R_H016                   !                                 
R354                 !    1997.70 !     611.00 !      270 !        ! SMC_0402R_H016                   !                                 
R363                 !    3350.00 !    2885.00 !      270 !      m ! SMC_0402R_H016                   !                                 
R387                 !     326.00 !    1547.98 !       90 !        ! SMC_0402R_H016                   !                                 
R390                 !     800.00 !    1200.00 !      180 !        ! SMC_0402R_H016                   !                                 
R393                 !     332.00 !    2685.08 !       90 !        ! SMC_0402R_H016                   !                                 
R396                 !     766.47 !    1885.00 !      180 !        ! SMC_0402R_H016                   !                                 
R399                 !     330.00 !    3210.00 !       90 !        ! SMC_0402R_H016                   !                                 
R428                 !    6170.00 !    1555.00 !      270 !      m ! SMC_0402R_H016                   !                                 
R429                 !    6170.00 !    1655.00 !      270 !      m ! SMC_0402R_H016                   !                                 
R430                 !    6155.00 !    1790.00 !       90 !      m ! SMC_0402R_H016                   !                                 
R431                 !    5980.00 !    1440.00 !       90 !      m ! SMC_0402R_H016                   !                                 
R432                 !    5980.00 !    1560.00 !       90 !      m ! SMC_0402R_H016                   !                                 
R433                 !    5980.00 !    1655.00 !       90 !      m ! SMC_0402R_H016                   !                                 
R434                 !    5980.00 !    1760.00 !       90 !      m ! SMC_0402R_H016                   !                                 
R448                 !    3860.00 !    3810.00 !      180 !        ! SMC_0402R_H016                   !                                 
R449                 !    3860.00 !    3758.00 !      180 !        ! SMC_0402R_H016                   !                                 
R461                 !    3994.00 !    3291.00 !        0 !        ! SMC_0402R_H016                   !                                 
R462                 !    3994.00 !    3239.00 !        0 !        ! SMC_0402R_H016                   !                                 
R467                 !     950.00 !    3585.00 !      270 !      m ! SMC_0402R_H016                   !                                 
R468                 !     882.00 !    3574.00 !      270 !      m ! SMC_0402R_H016                   !                                 
R469                 !     890.00 !    3500.00 !      180 !      m ! SMC_0402R_H016                   !                                 
R470                 !     890.00 !    3410.00 !      180 !      m ! SMC_0402R_H016                   !                                 
R485                 !    4715.00 !     965.00 !        0 !        ! SMC_0402R_H016                   !                                 
R486                 !    4715.00 !     915.00 !        0 !        ! SMC_0402R_H016                   !                                 
R386                 !     416.00 !    1547.98 !       90 !        ! SMC_0402R_H016                   !                                 
R389                 !     800.00 !    1300.00 !      180 !        ! SMC_0402R_H016                   !                                 
R392                 !     377.00 !    2685.08 !       90 !        ! SMC_0402R_H016                   !                                 
R395                 !     766.47 !    1930.00 !      180 !        ! SMC_0402R_H016                   !                                 
R398                 !     430.00 !    3210.00 !       90 !        ! SMC_0402R_H016                   !                                 
R385                 !     191.00 !    1547.98 !       90 !        ! SMC_0402R_H016                   !                                 
R388                 !     800.00 !    1050.00 !      180 !        ! SMC_0402R_H016                   !                                 
R391                 !     197.00 !    2685.08 !       90 !        ! SMC_0402R_H016                   !                                 
R394                 !     766.47 !    1750.00 !      180 !        ! SMC_0402R_H016                   !                                 
R397                 !     180.00 !    3210.00 !       90 !        ! SMC_0402R_H016                   !                                 
R406                 !    2262.80 !    3266.00 !       90 !        ! SMC_0402R_H016                   !                                 
R407                 !    5935.00 !    1080.00 !        0 !        ! SMC_0402R_H016                   !                                 
R139                 !    5550.00 !    4070.00 !        0 !      m ! SMC_0402R_H016                   !                                 
R195                 !    4905.00 !    1810.00 !        0 !      m ! SMC_0402R_H016                   !                                 
R203                 !    3485.00 !    3415.00 !      180 !      m ! SMC_0402R_H016                   !                                 
R204                 !    3765.00 !    3325.00 !        0 !      m ! SMC_0402R_H016                   !                                 
R205                 !    3765.00 !    3415.00 !        0 !      m ! SMC_0402R_H016                   !                                 
R206                 !    3485.00 !    3235.00 !      180 !      m ! SMC_0402R_H016                   !                                 
R57                  !    2975.00 !     574.41 !        0 !        ! SMC_0402R_H016                   !                                 
R332                 !     660.00 !    3035.00 !       90 !      m ! SMC_0402R_H016                   !                                 
R345                 !    1194.70 !     658.60 !      180 !        ! SMC_0402R_H016                   !                                 
R167                 !    3710.00 !    2710.00 !        0 !        ! SMC_0402R_H016                   !                                 
R3                   !     830.00 !     665.00 !        0 !      m ! SMC_0402R_H016                   !                                 
R158                 !    1330.00 !     753.00 !      180 !      m ! SMC_0402R_H016                   !                                 
R160                 !     788.00 !     932.00 !      270 !      m ! SMC_0402R_H016                   !                                 
R162                 !     743.00 !     932.00 !      270 !      m ! SMC_0402R_H016                   !                                 
R500                 !    4698.70 !    1685.95 !        0 !      m ! SMC_0402R_C_H016                 !                                 
R501                 !    4660.00 !    1755.00 !        0 !      m ! SMC_0402R_H016                   !                                 
R503                 !    4698.71 !    2079.65 !      180 !      m ! SMC_0402R_C_H016                 !                                 
R504                 !    4718.39 !    2138.71 !      270 !      m ! SMC_0402R_C_H016                 !                                 
R24                  !     868.00 !     710.00 !      180 !      m ! SMC_0402R_H016                   !                                 
R159                 !     878.00 !     932.00 !       90 !      m ! SMC_0402R_H016                   !                                 
R161                 !     833.00 !     932.00 !       90 !      m ! SMC_0402R_H016                   !                                 
R163                 !     698.00 !     932.00 !       90 !      m ! SMC_0402R_H016                   !                                 
R171                 !    3978.00 !    2531.00 !       90 !      m ! SMC_0402R_H016                   !                                 
R173                 !    3919.00 !    2531.00 !       90 !      m ! SMC_0402R_H016                   !                                 
R249                 !    5600.00 !    2345.00 !      270 !      m ! SMC_0402R_H016                   !                                 
R284                 !    3860.00 !    2531.00 !       90 !      m ! SMC_0402R_H016                   !                                 
R286                 !    3801.00 !    2531.00 !       90 !      m ! SMC_0402R_H016                   !                                 
R293                 !    4037.00 !    2531.00 !       90 !      m ! SMC_0402R_H016                   !                                 
R309                 !    4093.00 !    2531.00 !       90 !      m ! SMC_0402R_H016                   !                                 
R326                 !    4209.00 !    2531.00 !       90 !      m ! SMC_0402R_H016                   !                                 
R328                 !    4150.00 !    2531.00 !       90 !      m ! SMC_0402R_H016                   !                                 
R344                 !    1059.00 !     718.00 !        0 !      m ! SMC_0402R_H016                   !                                 
R450                 !    3860.00 !    3810.00 !        0 !      m ! SMC_0402R_H016                   !                                 
R452                 !    4405.00 !    3700.00 !        0 !        ! SMC_0402R_H016                   !                                 
R457                 !    3994.00 !    3291.00 !      180 !      m ! SMC_0402R_H016                   !                                 
R482                 !    4715.00 !     965.00 !      180 !      m ! SMC_0402R_H016                   !                                 
R487                 !    1835.00 !    2960.00 !      270 !        ! SMC_0402R_H016                   !                                 
R63                  !    2976.00 !     621.00 !        0 !        ! SMC_0402R_H016                   !                                 
R281                 !     850.00 !    2423.00 !      270 !      m ! SMC_0402R_H016                   !                                 
R282                 !     715.00 !    2423.00 !      270 !      m ! SMC_0402R_H016                   !                                 
R314                 !     896.00 !    2423.00 !      270 !      m ! SMC_0402R_H016                   !                                 
R320                 !    4375.00 !    3865.00 !      180 !        ! SMC_0402R_H016                   !                                 
R323                 !    4375.00 !    4015.00 !        0 !        ! SMC_0402R_H016                   !                                 
R44                  !    2910.00 !    2320.00 !       90 !      m ! SMC_0402R_H016                   !                                 
R402                 !    5452.50 !    2658.50 !      270 !      m ! SMC_0402R_H016                   !                                 
R408                 !    2083.00 !    2952.00 !       90 !        ! SMC_0402R_H016                   !                                 
R410                 !    6400.00 !     965.00 !      180 !        ! SMC_0402R_H016                   !                                 
R412                 !    2128.00 !    2952.00 !       90 !        ! SMC_0402R_H016                   !                                 
R414                 !    6400.00 !    1020.00 !      180 !        ! SMC_0402R_H016                   !                                 
R418                 !    2173.00 !    2952.00 !       90 !        ! SMC_0402R_H016                   !                                 
R419                 !    6400.00 !    1080.00 !      180 !        ! SMC_0402R_H016                   !                                 
R422                 !    1959.00 !    3268.00 !      270 !        ! SMC_0402R_H016                   !                                 
R423                 !    5935.00 !     965.00 !        0 !        ! SMC_0402R_H016                   !                                 
R331                 !     575.00 !    2070.00 !      270 !        ! SMC_0402R_H016                   !                                 
R361                 !     578.00 !    2590.00 !      270 !        ! SMC_0402R_H016                   !                                 
R365                 !     580.00 !    1465.00 !      270 !        ! SMC_0402R_H016                   !                                 
R368                 !     580.00 !     905.00 !      270 !        ! SMC_0402R_H016                   !                                 
R377                 !     505.00 !    1104.90 !       90 !        ! SMC_0402R_H016                   !                                 
R379                 !     577.00 !     676.00 !       90 !      m ! SMC_0402R_H016                   !                                 
R381                 !     514.52 !    2254.00 !       90 !        ! SMC_0402R_H016                   !                                 
R383                 !     535.00 !    1650.00 !        0 !        ! SMC_0402R_H016                   !                                 
R270                 !    4580.60 !    1882.80 !      180 !      m ! SMC_0402R_C_H016                 !                                 
R271                 !    4679.02 !    1863.12 !      270 !      m ! SMC_0402R_C_H016                 !                                 
R287                 !    3145.00 !    1645.00 !      180 !        ! SMC_0402R_H016                   !                                 
R288                 !    4905.00 !    1675.00 !      180 !        ! SMC_0402R_H016                   !                                 
R289                 !    3180.00 !    2209.00 !      180 !        ! SMC_0402R_H016                   !                                 
R290                 !    3275.00 !    2165.00 !        0 !        ! SMC_0402R_H016                   !                                 
R291                 !    3180.00 !    2389.00 !        0 !        ! SMC_0402R_H016                   !                                 
R296                 !    5920.53 !    2239.00 !        0 !        ! SMC_0402R_H016                   !                                 
R297                 !    5920.53 !    2284.02 !      180 !        ! SMC_0402R_H016                   !                                 
R300                 !    6019.02 !    1929.65 !       90 !      m ! SMC_0402R_H016                   !                                 
R301                 !    3180.00 !    2344.00 !      180 !        ! SMC_0402R_H016                   !                                 
R304                 !    3335.00 !    2532.00 !      270 !        ! SMC_0402R_H016                   !                                 
R306                 !    3180.00 !    2434.00 !        0 !        ! SMC_0402R_H016                   !                                 
R341                 !    3485.00 !    2885.00 !       90 !      m ! SMC_0402R_H016                   !                                 
R342                 !    3395.00 !    2885.00 !      270 !      m ! SMC_0402R_H016                   !                                 
R178                 !    3947.00 !    2680.00 !      180 !        ! SMC_0402R_H016                   !                                 
R179                 !    5270.00 !    2790.00 !      270 !        ! SMC_0402R_H016                   !                                 
R191                 !    3765.00 !    3235.00 !      180 !      m ! SMC_0402R_H016                   !                                 
R192                 !    3485.00 !    3325.00 !      180 !      m ! SMC_0402R_H016                   !                                 
R193                 !    4905.00 !    2115.00 !      180 !        ! SMC_0402R_H016                   !                                 
R194                 !    4980.00 !    1335.00 !      180 !        ! SMC_0402R_H016                   !                                 
R199                 !    3485.00 !    3370.00 !      180 !      m ! SMC_0402R_H016                   !                                 
R200                 !    3765.00 !    3280.00 !        0 !      m ! SMC_0402R_H016                   !                                 
R201                 !    3765.00 !    3370.00 !        0 !      m ! SMC_0402R_H016                   !                                 
R202                 !    3485.00 !    3280.00 !      180 !      m ! SMC_0402R_H016                   !                                 
R209                 !    4905.00 !    1765.00 !      180 !      m ! SMC_0402R_H016                   !                                 
R229                 !    5555.00 !     629.00 !      270 !      m ! SMC_0402R_H016                   !                                 
R235                 !    4205.00 !     900.00 !      270 !        ! SMC_0402R_H016                   !                                 
R236                 !    3770.00 !     895.00 !      270 !        ! SMC_0402R_H016                   !                                 
R243                 !    5410.00 !    2275.00 !      180 !      m ! SMC_0402R_H016                   !                                 
R18                  !    1055.00 !    3710.00 !       90 !      m ! SMC_0402R_H016                   !                                 
R21                  !    5935.00 !    1025.00 !        0 !        ! SMC_0402R_H016                   !                                 
R25                  !    2047.70 !     611.00 !      270 !        ! SMC_0402R_H016                   !                                 
R55                  !    2616.00 !     655.00 !      180 !        ! SMC_0402R_H016                   !                                 
R56                  !    2616.00 !     605.00 !        0 !        ! SMC_0402R_H016                   !                                 
R64                  !    5919.02 !    1929.65 !      270 !      m ! SMC_0402R_H016                   !                                 
R68                  !    5969.02 !    1929.65 !       90 !        ! SMC_0402R_H016                   !                                 
R70                  !     663.48 !    2709.00 !      180 !        ! SMC_0402R_H016                   !                                 
R71                  !     806.48 !    2810.00 !       90 !        ! SMC_0402R_H016                   !                                 
R74                  !    3440.00 !    2255.00 !      180 !      m ! SMC_0402R_H016                   !                                 
R75                  !    3350.00 !    2255.00 !        0 !      m ! SMC_0402R_H016                   !                                 
R99                  !    2540.00 !    2195.00 !       90 !      m ! SMC_0402R_H016                   !                                 
R104                 !    3604.00 !    1766.49 !      270 !        ! SMC_0402R_H016                   !                                 
R107                 !    2530.00 !    2375.00 !      180 !      m ! SMC_0402R_H016                   !                                 
R149                 !    3277.00 !    3205.00 !      180 !      m ! SMC_0402R_H016                   !                                 
R150                 !    3277.00 !    3340.00 !      180 !      m ! SMC_0402R_H016                   !                                 
R151                 !    3047.00 !    3350.00 !        0 !      m ! SMC_0402R_H016                   !                                 
R152                 !    3277.00 !    3250.00 !      180 !      m ! SMC_0402R_H016                   !                                 
R153                 !    3277.00 !    3295.00 !      180 !      m ! SMC_0402R_H016                   !                                 
R154                 !    3047.00 !    3305.00 !        0 !      m ! SMC_0402R_H016                   !                                 
R155                 !    3277.00 !    3430.00 !      180 !      m ! SMC_0402R_H016                   !                                 
R65                  !    6069.02 !    1929.65 !       90 !      m ! SMC_0402R_H016                   !                                 
R20                  !    5935.00 !    1125.00 !      180 !        ! SMC_0402R_H016                   !                                 
R114                 !    4735.00 !    3525.00 !      270 !        ! SMC_0402R_H016                   !                                 
R115                 !    4757.00 !    3551.00 !        0 !      m ! SMC_0402R_H016                   !                                 
R333                 !     335.00 !    2850.00 !      270 !      m ! SMC_0402R_H016                   !                                 
R335                 !     220.00 !    2925.00 !      180 !      m ! SMC_0402R_H016                   !                                 
R337                 !     220.00 !    2975.00 !      180 !      m ! SMC_0402R_H016                   !                                 
R340                 !     720.00 !    2915.00 !        0 !      m ! SMC_0402R_H016                   !                                 
R1992                !    1194.70 !     753.60 !      180 !        ! SMC_0402R_H016                   !                                 
TP11                 !     995.00 !    3700.00 !        0 !        ! TP010CT020B030_PTH               !                                 
TP12                 !    4795.00 !     925.00 !        0 !        ! TP010CT020B030_PTH               !                                 
TP13                 !    4080.00 !    3270.00 !        0 !        ! TP010CT020B030_PTH               !                                 
TP14                 !    3950.00 !    3820.00 !        0 !        ! TP010CT020B030_PTH               !                                 
TP15                 !    4670.00 !    3555.00 !        0 !        ! TP010CT020B030_PTH               !                                 
TP16                 !    3235.00 !    2630.00 !        0 !        ! TP010CT020B030_PTH               !                                 
TP17                 !    3305.00 !    2650.00 !        0 !        ! TP010CT020B030_PTH               !                                 
TP18                 !    3375.00 !    2650.00 !        0 !        ! TP010CT020B030_PTH               !                                 
TP19                 !    3445.00 !    2650.00 !        0 !        ! TP010CT020B030_PTH               !                                 
TP20                 !     755.00 !     620.00 !        0 !        ! TP010CT020B030_PTH               !                                 
TP21                 !    3370.00 !    3440.00 !        0 !        ! TP010CT020B030_PTH               !                                 
TP22                 !    5800.00 !    1048.00 !        0 !        ! TP010CT020B030_PTH               !                                 
TP23                 !    2017.00 !    3279.00 !      270 !        ! TP010CT020B030_PTH               !                                 
TP24                 !     636.00 !    2915.00 !        0 !        ! TP010CT020B030_PTH               !                                 
TP25                 !    4300.00 !    3865.00 !        0 !        ! TP010CT020B030_PTH               !                                 
TP26                 !    5955.00 !    2390.00 !        0 !        ! TP010CT020B030_PTH               !                                 
TP27                 !    5870.00 !    1840.00 !        0 !        ! TP010CT020B030_PTH               !                                 
TP28                 !     575.00 !    2265.00 !        0 !        ! TP010CT020B030_PTH               !                                 
TP29                 !     545.00 !    1710.00 !        0 !        ! TP010CT020B030_PTH               !                                 
TP30                 !     565.00 !    1130.00 !        0 !        ! TP010CT020B030_PTH               !                                 
TP31                 !     644.00 !     700.00 !        0 !        ! TP010CT020B030_PTH               !                                 
TP32                 !     647.00 !    2517.00 !        0 !        ! TP010CT020B030_PTH               !                                 
TP33                 !     620.00 !    1995.00 !        0 !        ! TP010CT020B030_PTH               !                                 
TP34                 !     645.00 !    1295.00 !        0 !        ! TP010CT020B030_PTH               !                                 
TP35                 !     635.00 !     845.00 !        0 !        ! TP010CT020B030_PTH               !                                 
TP36                 !    5600.00 !    4010.00 !        0 !        ! TP010CT020B030_PTH               !                                 
TP37                 !    5718.00 !    3965.00 !        0 !        ! TP010CT020B030_PTH               !                                 
TP38                 !    3745.00 !    4185.00 !        0 !        ! TP010CT020B030_PTH               !                                 
TP39                 !    5760.00 !    2465.00 !        0 !        ! TP010CT020B030_PTH               !                                 
TP40                 !    4831.00 !    2728.00 !        0 !        ! TP010CT020B030_PTH               !                                 
TP41                 !    5765.00 !     980.00 !        0 !        ! TP010CT020B030_PTH               !                                 
TP42                 !     978.00 !    3918.00 !        0 !        ! TP010CT020B030_PTH               !                                 
TP43                 !    5660.00 !    3470.00 !        0 !        ! TP010CT020B030_PTH               !                                 
TP44                 !    5300.00 !    4065.00 !        0 !        ! TP010CT020B030_PTH               !                                 
TP45                 !    4820.00 !    2125.00 !        0 !        ! TP010CT020B030_PTH               !                                 
TP46                 !    5410.00 !     960.00 !        0 !        ! TP010CT020B030_PTH               !                                 
TP47                 !    3746.00 !    1782.00 !        0 !        ! TP010CT020B030_PTH               !                                 
TP48                 !    2295.82 !     489.18 !        0 !        ! TP010CT020B030_PTH               !                                 
TP49                 !    4205.00 !     820.00 !        0 !        ! TP010CT020B030_PTH               !                                 
TP50                 !    3705.00 !     840.00 !        0 !        ! TP010CT020B030_PTH               !                                 
TP51                 !    3065.00 !    1695.00 !        0 !        ! TP010CT020B030_PTH               !                                 
TP62                 !    4970.00 !    1540.00 !        0 !        ! TP010CT020B030_PTH               !                                 
TP78                 !    3900.00 !    2325.00 !       90 !        ! TP010CT020B030_PTH               !                                 
TP180                !    3830.00 !    2325.00 !       90 !        ! TP010CT020B030_PTH               !                                 
TP181                !    3750.00 !    2100.00 !        0 !        ! TP010CT020B030_PTH               !                                 
TP182                !    3800.00 !    2100.00 !        0 !        ! TP010CT020B030_PTH               !                                 
TP183                !    4149.00 !    2298.00 !        0 !        ! TP010CT020B030_PTH               !                                 
TP184                !    4161.00 !    2354.00 !        0 !        ! TP010CT020B030_PTH               !                                 
TP185                !    4230.00 !    2354.00 !        0 !        ! TP010CT020B030_PTH               !                                 
TP186                !    3940.00 !    2235.00 !        0 !        ! TP010CT020B030_PTH               !                                 
TP187                !    4205.00 !    2295.00 !        0 !        ! TP010CT020B030_PTH               !                                 
TP188                !    4254.00 !    2296.00 !        0 !        ! TP010CT020B030_PTH               !                                 
TP193                !    4768.00 !    1207.00 !       90 !        ! TP010CT020B030_PTH               !                                 
TP194                !    4828.00 !    1103.00 !       90 !        ! TP010CT020B030_PTH               !                                 
TP195                !    4150.00 !    1235.00 !       90 !        ! TP010CT020B030_PTH               !                                 
TP196                !    4185.00 !    1170.00 !       90 !        ! TP010CT020B030_PTH               !                                 
TP199                !    4830.00 !    1330.00 !       90 !        ! TP010CT020B030_PTH               !                                 
TP200                !    4220.00 !    1235.00 !       90 !        ! TP010CT020B030_PTH               !                                 
TP201                !    4816.00 !    1258.00 !       90 !        ! TP010CT020B030_PTH               !                                 
TP202                !    4665.00 !    1104.00 !       90 !        ! TP010CT020B030_PTH               !                                 
TP203                !    4712.00 !    1157.00 !       90 !        ! TP010CT020B030_PTH               !                                 
TP204                !    4290.00 !    1235.00 !       90 !        ! TP010CT020B030_PTH               !                                 
TP10                 !     950.00 !    2915.00 !       90 !        ! TP010CT020B030_PTH               !                                 
TP132                !    4738.07 !    1548.16 !       90 !        ! TP010CT020B030_PTH               !                                 
TP133                !    4738.07 !    1508.79 !        0 !        ! TP010CT020B030_PTH               !                                 
TP134                !    5030.00 !    1550.00 !      270 !        ! TP010CT020B030_PTH               !                                 
TP135                !    4975.00 !    1485.00 !        0 !        ! TP010CT020B030_PTH               !                                 
TP136                !    4850.00 !    1540.00 !        0 !        ! TP010CT020B030_PTH               !                                 
TP137                !    4910.00 !    1540.00 !        0 !        ! TP010CT020B030_PTH               !                                 
TP138                !    5035.00 !    1490.00 !        0 !        ! TP010CT020B030_PTH               !                                 
TP139                !    4915.00 !    1485.00 !        0 !        ! TP010CT020B030_PTH               !                                 
TP140                !    4619.96 !    1626.90 !        0 !        ! TP010CT020B030_PTH               !                                 
TP141                !    4659.33 !    1626.90 !        0 !        ! TP010CT020B030_PTH               !                                 
TP1                  !    3320.00 !    3015.00 !       90 !        ! TP010CT020B030_PTH               !                                 
TP2                  !    3240.00 !    3010.00 !      270 !        ! TP010CT020B030_PTH               !                                 
TP3                  !    1535.00 !    3105.00 !      270 !        ! TP010CT020B030_PTH               !                                 
TP4                  !     710.00 !    3305.00 !      270 !        ! TP010CT020B030_PTH               !                                 
TP5                  !     780.00 !    3305.00 !        0 !        ! TP010CT020B030_PTH               !                                 
TP6                  !     795.00 !    3085.00 !        0 !        ! TP010CT020B030_PTH               !                                 
TP7                  !     875.00 !    2955.00 !        0 !        ! TP010CT020B030_PTH               !                                 
TP8                  !     885.00 !    3030.00 !       90 !        ! TP010CT020B030_PTH               !                                 
TP9                  !     945.00 !    2990.00 !        0 !        ! TP010CT020B030_PTH               !                                 
TP52                 !    5406.00 !    2346.00 !      180 !        ! TP010CT020B030_PTH               !                                 
TP53                 !    4290.00 !    2740.00 !        0 !        ! TP010CT020B030_PTH               !                                 
TP54                 !    5580.00 !    1615.00 !        0 !        ! TP010CT020B030_PTH               !                                 
TP55                 !    3655.00 !    2795.00 !       90 !        ! TP010CT020B030_PTH               !                                 
TP56                 !    5345.00 !    2536.00 !      180 !        ! TP010CT020B030_PTH               !                                 
TP57                 !    5445.00 !     795.00 !        0 !        ! TP010CT020B030_PTH               !                                 
TP58                 !    3580.00 !    2615.00 !        0 !        ! TP010CT020B030_PTH               !                                 
TP59                 !    3690.00 !    4135.00 !      180 !        ! TP010CT020B030_PTH               !                                 
TP60                 !    2250.00 !    3960.00 !        0 !        ! TP010CT020B030_PTH               !                                 
TP61                 !    3385.00 !    2135.00 !      180 !        ! TP010CT020B030_PTH               !                                 
Y1                   !    3570.00 !    2359.00 !       90 !        ! SMC_Y2_079X047                   !                                 
